(kicad_sch
	(version 20250114)
	(generator "eeschema")
	(generator_version "9.0")
	(paper "A3")
	(title_block
		(title "PolarFire SoM")
		(date "2025-07-22")
		(rev "1.1.4")
		(company "Antmicro Ltd")
		(comment 1 "www.antmicro.com")
	)
	(text "VDDA25"
		(exclude_from_sim no)
		(at 92.71 184.15 0)
		(effects
			(font
				(size 2 2)
				(thickness 0.8)
				(bold yes)
			)
			(justify left bottom)
		)
	)
	(text "GPIO Bank"
		(exclude_from_sim no)
		(at 161.925 234.315 0)
		(effects
			(font
				(size 2 2)
				(thickness 0.8)
				(bold yes)
			)
			(justify left bottom)
		)
	)
	(text "Bank 3 JTAG"
		(exclude_from_sim no)
		(at 22.225 208.915 0)
		(effects
			(font
				(size 2 2)
				(thickness 0.8)
				(bold yes)
			)
			(justify left bottom)
		)
	)
	(text "Bank 2"
		(exclude_from_sim no)
		(at 60.96 209.55 0)
		(effects
			(font
				(size 2 2)
				(thickness 0.8)
				(bold yes)
			)
			(justify left bottom)
		)
	)
	(text "SERDES_VREF"
		(exclude_from_sim no)
		(at 16.51 234.95 0)
		(effects
			(font
				(size 2 2)
				(thickness 0.8)
				(bold yes)
			)
			(justify left bottom)
		)
	)
	(text "VDD18"
		(exclude_from_sim no)
		(at 135.89 184.15 0)
		(effects
			(font
				(size 2 2)
				(thickness 0.8)
				(bold yes)
			)
			(justify left bottom)
		)
	)
	(text "VDDAUX(GPIO)"
		(exclude_from_sim no)
		(at 128.905 259.715 0)
		(effects
			(font
				(size 2 2)
				(thickness 0.8)
				(bold yes)
			)
			(justify left bottom)
		)
	)
	(text "Bank 5"
		(exclude_from_sim no)
		(at 26.67 184.15 0)
		(effects
			(font
				(size 2 2)
				(thickness 0.8)
				(bold yes)
			)
			(justify left bottom)
		)
	)
	(text "VDD"
		(exclude_from_sim no)
		(at 130.81 156.21 0)
		(effects
			(font
				(size 2 2)
				(thickness 0.8)
				(bold yes)
			)
			(justify left bottom)
		)
	)
	(text "Decoupling capacitors"
		(exclude_from_sim no)
		(at 57.15 144.78 0)
		(effects
			(font
				(size 4 4)
				(thickness 0.8)
				(bold yes)
			)
			(justify left bottom)
		)
	)
	(text "VDD25"
		(exclude_from_sim no)
		(at 106.68 209.55 0)
		(effects
			(font
				(size 2 2)
				(thickness 0.8)
				(bold yes)
			)
			(justify left bottom)
		)
	)
	(text "HSIO Bank"
		(exclude_from_sim no)
		(at 161.29 209.55 0)
		(effects
			(font
				(size 2 2)
				(thickness 0.8)
				(bold yes)
			)
			(justify left bottom)
		)
	)
	(text "VDDSREF"
		(exclude_from_sim no)
		(at 48.26 234.95 0)
		(effects
			(font
				(size 2 2)
				(thickness 0.8)
				(bold yes)
			)
			(justify left bottom)
		)
	)
	(text "Bank 4"
		(exclude_from_sim no)
		(at 59.69 184.15 0)
		(effects
			(font
				(size 2 2)
				(thickness 0.8)
				(bold yes)
			)
			(justify left bottom)
		)
	)
	(text "PolarFire power supply"
		(exclude_from_sim no)
		(at 14.605 20.32 0)
		(effects
			(font
				(size 4 4)
				(thickness 0.8)
				(bold yes)
			)
			(justify left bottom)
		)
	)
	(text "VDDA"
		(exclude_from_sim no)
		(at 104.14 234.95 0)
		(effects
			(font
				(size 2 2)
				(thickness 0.8)
				(bold yes)
			)
			(justify left bottom)
		)
	)
	(text "Bank 6 MSS DDR"
		(exclude_from_sim no)
		(at 33.02 154.94 0)
		(effects
			(font
				(size 2 2)
				(thickness 0.8)
				(bold yes)
			)
			(justify left bottom)
		)
	)
	(junction
		(at 119.38 240.03)
		(diameter 0)
		(color 0 0 0 0)
	)
	(junction
		(at 40.64 170.18)
		(diameter 0)
		(color 0 0 0 0)
	)
	(junction
		(at 139.7 189.23)
		(diameter 0)
		(color 0 0 0 0)
	)
	(junction
		(at 229.87 82.55)
		(diameter 0)
		(color 0 0 0 0)
	)
	(junction
		(at 50.8 162.56)
		(diameter 0)
		(color 0 0 0 0)
	)
	(junction
		(at 168.91 87.63)
		(diameter 0)
		(color 0 0 0 0)
	)
	(junction
		(at 132.08 222.25)
		(diameter 0)
		(color 0 0 0 0)
	)
	(junction
		(at 115.57 162.56)
		(diameter 0)
		(color 0 0 0 0)
	)
	(junction
		(at 60.96 189.23)
		(diameter 0)
		(color 0 0 0 0)
	)
	(junction
		(at 121.92 222.25)
		(diameter 0)
		(color 0 0 0 0)
	)
	(junction
		(at 152.4 215.9)
		(diameter 0)
		(color 0 0 0 0)
	)
	(junction
		(at 95.25 162.56)
		(diameter 0)
		(color 0 0 0 0)
	)
	(junction
		(at 96.52 189.23)
		(diameter 0)
		(color 0 0 0 0)
	)
	(junction
		(at 96.52 196.85)
		(diameter 0)
		(color 0 0 0 0)
	)
	(junction
		(at 109.22 247.65)
		(diameter 0)
		(color 0 0 0 0)
	)
	(junction
		(at 60.96 214.63)
		(diameter 0)
		(color 0 0 0 0)
	)
	(junction
		(at 129.54 247.65)
		(diameter 0)
		(color 0 0 0 0)
	)
	(junction
		(at 50.8 170.18)
		(diameter 0)
		(color 0 0 0 0)
	)
	(junction
		(at 182.88 240.03)
		(diameter 0)
		(color 0 0 0 0)
	)
	(junction
		(at 146.05 170.18)
		(diameter 0)
		(color 0 0 0 0)
	)
	(junction
		(at 125.73 162.56)
		(diameter 0)
		(color 0 0 0 0)
	)
	(junction
		(at 160.02 196.85)
		(diameter 0)
		(color 0 0 0 0)
	)
	(junction
		(at 176.53 87.63)
		(diameter 0)
		(color 0 0 0 0)
	)
	(junction
		(at 172.72 223.52)
		(diameter 0)
		(color 0 0 0 0)
	)
	(junction
		(at 179.07 92.71)
		(diameter 0)
		(color 0 0 0 0)
	)
	(junction
		(at 105.41 270.51)
		(diameter 0)
		(color 0 0 0 0)
	)
	(junction
		(at 60.96 162.56)
		(diameter 0)
		(color 0 0 0 0)
	)
	(junction
		(at 132.08 214.63)
		(diameter 0)
		(color 0 0 0 0)
	)
	(junction
		(at 176.53 170.18)
		(diameter 0)
		(color 0 0 0 0)
	)
	(junction
		(at 106.68 196.85)
		(diameter 0)
		(color 0 0 0 0)
	)
	(junction
		(at 149.86 196.85)
		(diameter 0)
		(color 0 0 0 0)
	)
	(junction
		(at 182.88 196.85)
		(diameter 0)
		(color 0 0 0 0)
	)
	(junction
		(at 71.12 222.25)
		(diameter 0)
		(color 0 0 0 0)
	)
	(junction
		(at 105.41 162.56)
		(diameter 0)
		(color 0 0 0 0)
	)
	(junction
		(at 115.57 170.18)
		(diameter 0)
		(color 0 0 0 0)
	)
	(junction
		(at 129.54 196.85)
		(diameter 0)
		(color 0 0 0 0)
	)
	(junction
		(at 166.37 162.56)
		(diameter 0)
		(color 0 0 0 0)
	)
	(junction
		(at 34.29 198.12)
		(diameter 0)
		(color 0 0 0 0)
	)
	(junction
		(at 30.48 170.18)
		(diameter 0)
		(color 0 0 0 0)
	)
	(junction
		(at 166.37 170.18)
		(diameter 0)
		(color 0 0 0 0)
	)
	(junction
		(at 152.4 240.03)
		(diameter 0)
		(color 0 0 0 0)
	)
	(junction
		(at 172.72 240.03)
		(diameter 0)
		(color 0 0 0 0)
	)
	(junction
		(at 115.57 278.13)
		(diameter 0)
		(color 0 0 0 0)
	)
	(junction
		(at 246.38 85.09)
		(diameter 0)
		(color 0 0 0 0)
	)
	(junction
		(at 71.12 196.85)
		(diameter 0)
		(color 0 0 0 0)
	)
	(junction
		(at 182.88 223.52)
		(diameter 0)
		(color 0 0 0 0)
	)
	(junction
		(at 34.29 223.52)
		(diameter 0)
		(color 0 0 0 0)
	)
	(junction
		(at 30.48 162.56)
		(diameter 0)
		(color 0 0 0 0)
	)
	(junction
		(at 149.86 189.23)
		(diameter 0)
		(color 0 0 0 0)
	)
	(junction
		(at 166.37 270.51)
		(diameter 0)
		(color 0 0 0 0)
	)
	(junction
		(at 162.56 223.52)
		(diameter 0)
		(color 0 0 0 0)
	)
	(junction
		(at 172.72 247.65)
		(diameter 0)
		(color 0 0 0 0)
	)
	(junction
		(at 146.05 278.13)
		(diameter 0)
		(color 0 0 0 0)
	)
	(junction
		(at 176.53 162.56)
		(diameter 0)
		(color 0 0 0 0)
	)
	(junction
		(at 156.21 162.56)
		(diameter 0)
		(color 0 0 0 0)
	)
	(junction
		(at 129.54 189.23)
		(diameter 0)
		(color 0 0 0 0)
	)
	(junction
		(at 139.7 196.85)
		(diameter 0)
		(color 0 0 0 0)
	)
	(junction
		(at 176.53 278.13)
		(diameter 0)
		(color 0 0 0 0)
	)
	(junction
		(at 162.56 240.03)
		(diameter 0)
		(color 0 0 0 0)
	)
	(junction
		(at 162.56 215.9)
		(diameter 0)
		(color 0 0 0 0)
	)
	(junction
		(at 20.32 162.56)
		(diameter 0)
		(color 0 0 0 0)
	)
	(junction
		(at 99.06 247.65)
		(diameter 0)
		(color 0 0 0 0)
	)
	(junction
		(at 71.12 162.56)
		(diameter 0)
		(color 0 0 0 0)
	)
	(junction
		(at 129.54 240.03)
		(diameter 0)
		(color 0 0 0 0)
	)
	(junction
		(at 24.13 190.5)
		(diameter 0)
		(color 0 0 0 0)
	)
	(junction
		(at 135.89 170.18)
		(diameter 0)
		(color 0 0 0 0)
	)
	(junction
		(at 86.36 189.23)
		(diameter 0)
		(color 0 0 0 0)
	)
	(junction
		(at 139.7 247.65)
		(diameter 0)
		(color 0 0 0 0)
	)
	(junction
		(at 111.76 222.25)
		(diameter 0)
		(color 0 0 0 0)
	)
	(junction
		(at 121.92 214.63)
		(diameter 0)
		(color 0 0 0 0)
	)
	(junction
		(at 172.72 215.9)
		(diameter 0)
		(color 0 0 0 0)
	)
	(junction
		(at 88.9 247.65)
		(diameter 0)
		(color 0 0 0 0)
	)
	(junction
		(at 146.05 162.56)
		(diameter 0)
		(color 0 0 0 0)
	)
	(junction
		(at 60.96 170.18)
		(diameter 0)
		(color 0 0 0 0)
	)
	(junction
		(at 78.74 240.03)
		(diameter 0)
		(color 0 0 0 0)
	)
	(junction
		(at 111.76 214.63)
		(diameter 0)
		(color 0 0 0 0)
	)
	(junction
		(at 40.64 162.56)
		(diameter 0)
		(color 0 0 0 0)
	)
	(junction
		(at 99.06 240.03)
		(diameter 0)
		(color 0 0 0 0)
	)
	(junction
		(at 119.38 247.65)
		(diameter 0)
		(color 0 0 0 0)
	)
	(junction
		(at 45.72 240.03)
		(diameter 0)
		(color 0 0 0 0)
	)
	(junction
		(at 101.6 222.25)
		(diameter 0)
		(color 0 0 0 0)
	)
	(junction
		(at 88.9 240.03)
		(diameter 0)
		(color 0 0 0 0)
	)
	(junction
		(at 156.21 170.18)
		(diameter 0)
		(color 0 0 0 0)
	)
	(junction
		(at 91.44 214.63)
		(diameter 0)
		(color 0 0 0 0)
	)
	(junction
		(at 135.89 162.56)
		(diameter 0)
		(color 0 0 0 0)
	)
	(junction
		(at 135.89 270.51)
		(diameter 0)
		(color 0 0 0 0)
	)
	(junction
		(at 182.88 247.65)
		(diameter 0)
		(color 0 0 0 0)
	)
	(junction
		(at 242.57 92.71)
		(diameter 0)
		(color 0 0 0 0)
	)
	(junction
		(at 162.56 247.65)
		(diameter 0)
		(color 0 0 0 0)
	)
	(junction
		(at 71.12 170.18)
		(diameter 0)
		(color 0 0 0 0)
	)
	(junction
		(at 119.38 189.23)
		(diameter 0)
		(color 0 0 0 0)
	)
	(junction
		(at 24.13 215.9)
		(diameter 0)
		(color 0 0 0 0)
	)
	(junction
		(at 125.73 170.18)
		(diameter 0)
		(color 0 0 0 0)
	)
	(junction
		(at 105.41 170.18)
		(diameter 0)
		(color 0 0 0 0)
	)
	(junction
		(at 55.88 247.65)
		(diameter 0)
		(color 0 0 0 0)
	)
	(junction
		(at 101.6 214.63)
		(diameter 0)
		(color 0 0 0 0)
	)
	(junction
		(at 172.72 189.23)
		(diameter 0)
		(color 0 0 0 0)
	)
	(junction
		(at 109.22 240.03)
		(diameter 0)
		(color 0 0 0 0)
	)
	(wire
		(pts
			(xy 71.12 223.52) (xy 71.12 222.25)
		)
		(stroke
			(width 0)
			(type default)
		)
	)
	(wire
		(pts
			(xy 160.02 195.58) (xy 160.02 196.85)
		)
		(stroke
			(width 0)
			(type default)
		)
	)
	(wire
		(pts
			(xy 125.73 162.56) (xy 125.73 163.83)
		)
		(stroke
			(width 0)
			(type default)
		)
	)
	(wire
		(pts
			(xy 132.08 220.98) (xy 132.08 222.25)
		)
		(stroke
			(width 0)
			(type default)
		)
	)
	(wire
		(pts
			(xy 96.52 196.85) (xy 106.68 196.85)
		)
		(stroke
			(width 0)
			(type default)
		)
	)
	(wire
		(pts
			(xy 125.73 162.56) (xy 135.89 162.56)
		)
		(stroke
			(width 0)
			(type default)
		)
	)
	(wire
		(pts
			(xy 20.32 168.91) (xy 20.32 170.18)
		)
		(stroke
			(width 0)
			(type default)
		)
	)
	(wire
		(pts
			(xy 106.68 195.58) (xy 106.68 196.85)
		)
		(stroke
			(width 0)
			(type default)
		)
	)
	(wire
		(pts
			(xy 182.88 224.79) (xy 182.88 223.52)
		)
		(stroke
			(width 0)
			(type default)
		)
	)
	(wire
		(pts
			(xy 166.37 168.91) (xy 166.37 170.18)
		)
		(stroke
			(width 0)
			(type default)
		)
	)
	(wire
		(pts
			(xy 176.53 87.63) (xy 194.31 87.63)
		)
		(stroke
			(width 0)
			(type default)
		)
	)
	(wire
		(pts
			(xy 119.38 240.03) (xy 119.38 241.3)
		)
		(stroke
			(width 0)
			(type default)
		)
	)
	(wire
		(pts
			(xy 246.38 85.09) (xy 248.92 85.09)
		)
		(stroke
			(width 0)
			(type default)
		)
	)
	(wire
		(pts
			(xy 172.72 240.03) (xy 172.72 241.3)
		)
		(stroke
			(width 0)
			(type default)
		)
	)
	(wire
		(pts
			(xy 227.33 95.25) (xy 229.87 95.25)
		)
		(stroke
			(width 0)
			(type default)
		)
	)
	(wire
		(pts
			(xy 182.88 246.38) (xy 182.88 247.65)
		)
		(stroke
			(width 0)
			(type default)
		)
	)
	(polyline
		(pts
			(xy 146.05 204.47) (xy 146.05 255.27)
		)
		(stroke
			(width 0)
			(type default)
		)
	)
	(wire
		(pts
			(xy 24.13 222.25) (xy 24.13 223.52)
		)
		(stroke
			(width 0)
			(type default)
		)
	)
	(wire
		(pts
			(xy 101.6 214.63) (xy 101.6 215.9)
		)
		(stroke
			(width 0)
			(type default)
		)
	)
	(wire
		(pts
			(xy 60.96 214.63) (xy 60.96 215.9)
		)
		(stroke
			(width 0)
			(type default)
		)
	)
	(wire
		(pts
			(xy 139.7 189.23) (xy 139.7 190.5)
		)
		(stroke
			(width 0)
			(type default)
		)
	)
	(wire
		(pts
			(xy 20.32 170.18) (xy 30.48 170.18)
		)
		(stroke
			(width 0)
			(type default)
		)
	)
	(wire
		(pts
			(xy 55.88 240.03) (xy 55.88 241.3)
		)
		(stroke
			(width 0)
			(type default)
		)
	)
	(wire
		(pts
			(xy 135.89 276.86) (xy 135.89 278.13)
		)
		(stroke
			(width 0)
			(type default)
		)
	)
	(wire
		(pts
			(xy 96.52 189.23) (xy 106.68 189.23)
		)
		(stroke
			(width 0)
			(type default)
		)
	)
	(wire
		(pts
			(xy 172.72 195.58) (xy 172.72 196.85)
		)
		(stroke
			(width 0)
			(type default)
		)
	)
	(wire
		(pts
			(xy 101.6 222.25) (xy 111.76 222.25)
		)
		(stroke
			(width 0)
			(type default)
		)
	)
	(wire
		(pts
			(xy 105.41 162.56) (xy 105.41 163.83)
		)
		(stroke
			(width 0)
			(type default)
		)
	)
	(wire
		(pts
			(xy 111.76 214.63) (xy 111.76 215.9)
		)
		(stroke
			(width 0)
			(type default)
		)
	)
	(wire
		(pts
			(xy 229.87 82.55) (xy 229.87 87.63)
		)
		(stroke
			(width 0)
			(type default)
		)
	)
	(wire
		(pts
			(xy 176.53 168.91) (xy 176.53 170.18)
		)
		(stroke
			(width 0)
			(type default)
		)
	)
	(wire
		(pts
			(xy 135.89 162.56) (xy 135.89 163.83)
		)
		(stroke
			(width 0)
			(type default)
		)
	)
	(wire
		(pts
			(xy 179.07 92.71) (xy 194.31 92.71)
		)
		(stroke
			(width 0)
			(type default)
		)
	)
	(wire
		(pts
			(xy 168.91 85.09) (xy 168.91 87.63)
		)
		(stroke
			(width 0)
			(type default)
		)
	)
	(wire
		(pts
			(xy 71.12 161.29) (xy 71.12 162.56)
		)
		(stroke
			(width 0)
			(type default)
		)
	)
	(wire
		(pts
			(xy 229.87 82.55) (xy 231.14 82.55)
		)
		(stroke
			(width 0)
			(type default)
		)
	)
	(wire
		(pts
			(xy 115.57 162.56) (xy 125.73 162.56)
		)
		(stroke
			(width 0)
			(type default)
		)
	)
	(wire
		(pts
			(xy 132.08 213.36) (xy 132.08 214.63)
		)
		(stroke
			(width 0)
			(type default)
		)
	)
	(wire
		(pts
			(xy 105.41 270.51) (xy 115.57 270.51)
		)
		(stroke
			(width 0)
			(type default)
		)
	)
	(wire
		(pts
			(xy 135.89 170.18) (xy 146.05 170.18)
		)
		(stroke
			(width 0)
			(type default)
		)
	)
	(wire
		(pts
			(xy 24.13 190.5) (xy 24.13 191.77)
		)
		(stroke
			(width 0)
			(type default)
		)
	)
	(polyline
		(pts
			(xy 12.7 255.27) (xy 191.77 255.27)
		)
		(stroke
			(width 0)
			(type default)
		)
	)
	(wire
		(pts
			(xy 78.74 246.38) (xy 78.74 247.65)
		)
		(stroke
			(width 0)
			(type default)
		)
	)
	(wire
		(pts
			(xy 242.57 92.71) (xy 242.57 93.98)
		)
		(stroke
			(width 0)
			(type default)
		)
	)
	(wire
		(pts
			(xy 115.57 170.18) (xy 125.73 170.18)
		)
		(stroke
			(width 0)
			(type default)
		)
	)
	(wire
		(pts
			(xy 176.53 171.45) (xy 176.53 170.18)
		)
		(stroke
			(width 0)
			(type default)
		)
	)
	(wire
		(pts
			(xy 166.37 270.51) (xy 166.37 271.78)
		)
		(stroke
			(width 0)
			(type default)
		)
	)
	(wire
		(pts
			(xy 135.89 162.56) (xy 146.05 162.56)
		)
		(stroke
			(width 0)
			(type default)
		)
	)
	(wire
		(pts
			(xy 242.57 92.71) (xy 248.92 92.71)
		)
		(stroke
			(width 0)
			(type default)
		)
	)
	(wire
		(pts
			(xy 166.37 162.56) (xy 176.53 162.56)
		)
		(stroke
			(width 0)
			(type default)
		)
	)
	(wire
		(pts
			(xy 139.7 246.38) (xy 139.7 247.65)
		)
		(stroke
			(width 0)
			(type default)
		)
	)
	(wire
		(pts
			(xy 139.7 189.23) (xy 149.86 189.23)
		)
		(stroke
			(width 0)
			(type default)
		)
	)
	(wire
		(pts
			(xy 156.21 162.56) (xy 156.21 163.83)
		)
		(stroke
			(width 0)
			(type default)
		)
	)
	(wire
		(pts
			(xy 129.54 240.03) (xy 129.54 241.3)
		)
		(stroke
			(width 0)
			(type default)
		)
	)
	(wire
		(pts
			(xy 135.89 270.51) (xy 135.89 271.78)
		)
		(stroke
			(width 0)
			(type default)
		)
	)
	(wire
		(pts
			(xy 152.4 240.03) (xy 162.56 240.03)
		)
		(stroke
			(width 0)
			(type default)
		)
	)
	(wire
		(pts
			(xy 135.89 269.24) (xy 135.89 270.51)
		)
		(stroke
			(width 0)
			(type default)
		)
	)
	(polyline
		(pts
			(xy 12.7 229.87) (xy 191.77 229.87)
		)
		(stroke
			(width 0)
			(type default)
		)
	)
	(wire
		(pts
			(xy 20.32 246.38) (xy 20.32 248.92)
		)
		(stroke
			(width 0)
			(type default)
		)
	)
	(wire
		(pts
			(xy 60.96 222.25) (xy 71.12 222.25)
		)
		(stroke
			(width 0)
			(type default)
		)
	)
	(wire
		(pts
			(xy 88.9 240.03) (xy 99.06 240.03)
		)
		(stroke
			(width 0)
			(type default)
		)
	)
	(wire
		(pts
			(xy 71.12 171.45) (xy 71.12 170.18)
		)
		(stroke
			(width 0)
			(type default)
		)
	)
	(wire
		(pts
			(xy 86.36 189.23) (xy 96.52 189.23)
		)
		(stroke
			(width 0)
			(type default)
		)
	)
	(wire
		(pts
			(xy 194.31 85.09) (xy 191.77 85.09)
		)
		(stroke
			(width 0)
			(type default)
		)
	)
	(wire
		(pts
			(xy 135.89 278.13) (xy 146.05 278.13)
		)
		(stroke
			(width 0)
			(type default)
		)
	)
	(wire
		(pts
			(xy 168.91 87.63) (xy 168.91 90.17)
		)
		(stroke
			(width 0)
			(type default)
		)
	)
	(wire
		(pts
			(xy 132.08 214.63) (xy 132.08 215.9)
		)
		(stroke
			(width 0)
			(type default)
		)
	)
	(wire
		(pts
			(xy 111.76 222.25) (xy 121.92 222.25)
		)
		(stroke
			(width 0)
			(type default)
		)
	)
	(wire
		(pts
			(xy 149.86 196.85) (xy 160.02 196.85)
		)
		(stroke
			(width 0)
			(type default)
		)
	)
	(wire
		(pts
			(xy 45.72 247.65) (xy 55.88 247.65)
		)
		(stroke
			(width 0)
			(type default)
		)
	)
	(wire
		(pts
			(xy 129.54 196.85) (xy 139.7 196.85)
		)
		(stroke
			(width 0)
			(type default)
		)
	)
	(wire
		(pts
			(xy 146.05 279.4) (xy 146.05 278.13)
		)
		(stroke
			(width 0)
			(type default)
		)
	)
	(wire
		(pts
			(xy 71.12 162.56) (xy 71.12 163.83)
		)
		(stroke
			(width 0)
			(type default)
		)
	)
	(wire
		(pts
			(xy 91.44 214.63) (xy 101.6 214.63)
		)
		(stroke
			(width 0)
			(type default)
		)
	)
	(wire
		(pts
			(xy 34.29 190.5) (xy 34.29 191.77)
		)
		(stroke
			(width 0)
			(type default)
		)
	)
	(wire
		(pts
			(xy 162.56 215.9) (xy 172.72 215.9)
		)
		(stroke
			(width 0)
			(type default)
		)
	)
	(wire
		(pts
			(xy 86.36 189.23) (xy 86.36 190.5)
		)
		(stroke
			(width 0)
			(type default)
		)
	)
	(wire
		(pts
			(xy 24.13 196.85) (xy 24.13 198.12)
		)
		(stroke
			(width 0)
			(type default)
		)
	)
	(wire
		(pts
			(xy 24.13 189.23) (xy 24.13 190.5)
		)
		(stroke
			(width 0)
			(type default)
		)
	)
	(wire
		(pts
			(xy 20.32 162.56) (xy 30.48 162.56)
		)
		(stroke
			(width 0)
			(type default)
		)
	)
	(wire
		(pts
			(xy 50.8 162.56) (xy 60.96 162.56)
		)
		(stroke
			(width 0)
			(type default)
		)
	)
	(wire
		(pts
			(xy 99.06 240.03) (xy 109.22 240.03)
		)
		(stroke
			(width 0)
			(type default)
		)
	)
	(wire
		(pts
			(xy 105.41 270.51) (xy 105.41 271.78)
		)
		(stroke
			(width 0)
			(type default)
		)
	)
	(wire
		(pts
			(xy 193.04 95.25) (xy 194.31 95.25)
		)
		(stroke
			(width 0)
			(type default)
		)
	)
	(wire
		(pts
			(xy 182.88 189.23) (xy 182.88 190.5)
		)
		(stroke
			(width 0)
			(type default)
		)
	)
	(wire
		(pts
			(xy 149.86 195.58) (xy 149.86 196.85)
		)
		(stroke
			(width 0)
			(type default)
		)
	)
	(wire
		(pts
			(xy 86.36 196.85) (xy 96.52 196.85)
		)
		(stroke
			(width 0)
			(type default)
		)
	)
	(wire
		(pts
			(xy 105.41 162.56) (xy 115.57 162.56)
		)
		(stroke
			(width 0)
			(type default)
		)
	)
	(wire
		(pts
			(xy 55.88 246.38) (xy 55.88 247.65)
		)
		(stroke
			(width 0)
			(type default)
		)
	)
	(wire
		(pts
			(xy 30.48 162.56) (xy 40.64 162.56)
		)
		(stroke
			(width 0)
			(type default)
		)
	)
	(polyline
		(pts
			(xy 168.91 179.07) (xy 168.91 204.47)
		)
		(stroke
			(width 0)
			(type default)
		)
	)
	(wire
		(pts
			(xy 24.13 198.12) (xy 34.29 198.12)
		)
		(stroke
			(width 0)
			(type default)
		)
	)
	(wire
		(pts
			(xy 105.41 276.86) (xy 105.41 278.13)
		)
		(stroke
			(width 0)
			(type default)
		)
	)
	(wire
		(pts
			(xy 176.53 162.56) (xy 176.53 163.83)
		)
		(stroke
			(width 0)
			(type default)
		)
	)
	(wire
		(pts
			(xy 91.44 213.36) (xy 91.44 214.63)
		)
		(stroke
			(width 0)
			(type default)
		)
	)
	(wire
		(pts
			(xy 101.6 220.98) (xy 101.6 222.25)
		)
		(stroke
			(width 0)
			(type default)
		)
	)
	(wire
		(pts
			(xy 40.64 162.56) (xy 50.8 162.56)
		)
		(stroke
			(width 0)
			(type default)
		)
	)
	(wire
		(pts
			(xy 50.8 168.91) (xy 50.8 170.18)
		)
		(stroke
			(width 0)
			(type default)
		)
	)
	(wire
		(pts
			(xy 176.53 161.29) (xy 176.53 162.56)
		)
		(stroke
			(width 0)
			(type default)
		)
	)
	(wire
		(pts
			(xy 71.12 220.98) (xy 71.12 222.25)
		)
		(stroke
			(width 0)
			(type default)
		)
	)
	(wire
		(pts
			(xy 172.72 223.52) (xy 182.88 223.52)
		)
		(stroke
			(width 0)
			(type default)
		)
	)
	(wire
		(pts
			(xy 129.54 195.58) (xy 129.54 196.85)
		)
		(stroke
			(width 0)
			(type default)
		)
	)
	(wire
		(pts
			(xy 125.73 170.18) (xy 135.89 170.18)
		)
		(stroke
			(width 0)
			(type default)
		)
	)
	(wire
		(pts
			(xy 156.21 162.56) (xy 166.37 162.56)
		)
		(stroke
			(width 0)
			(type default)
		)
	)
	(wire
		(pts
			(xy 152.4 246.38) (xy 152.4 247.65)
		)
		(stroke
			(width 0)
			(type default)
		)
	)
	(wire
		(pts
			(xy 227.33 92.71) (xy 242.57 92.71)
		)
		(stroke
			(width 0)
			(type default)
		)
	)
	(wire
		(pts
			(xy 129.54 247.65) (xy 139.7 247.65)
		)
		(stroke
			(width 0)
			(type default)
		)
	)
	(wire
		(pts
			(xy 115.57 276.86) (xy 115.57 278.13)
		)
		(stroke
			(width 0)
			(type default)
		)
	)
	(polyline
		(pts
			(xy 72.39 229.87) (xy 72.39 255.27)
		)
		(stroke
			(width 0)
			(type default)
		)
	)
	(wire
		(pts
			(xy 162.56 222.25) (xy 162.56 223.52)
		)
		(stroke
			(width 0)
			(type default)
		)
	)
	(wire
		(pts
			(xy 182.88 222.25) (xy 182.88 223.52)
		)
		(stroke
			(width 0)
			(type default)
		)
	)
	(wire
		(pts
			(xy 227.33 82.55) (xy 229.87 82.55)
		)
		(stroke
			(width 0)
			(type default)
		)
	)
	(wire
		(pts
			(xy 194.31 80.01) (xy 191.77 80.01)
		)
		(stroke
			(width 0)
			(type default)
		)
	)
	(polyline
		(pts
			(xy 191.77 138.43) (xy 191.77 284.48)
		)
		(stroke
			(width 0)
			(type default)
		)
	)
	(wire
		(pts
			(xy 166.37 269.24) (xy 166.37 270.51)
		)
		(stroke
			(width 0)
			(type default)
		)
	)
	(wire
		(pts
			(xy 119.38 189.23) (xy 119.38 190.5)
		)
		(stroke
			(width 0)
			(type default)
		)
	)
	(wire
		(pts
			(xy 45.72 238.76) (xy 45.72 240.03)
		)
		(stroke
			(width 0)
			(type default)
		)
	)
	(polyline
		(pts
			(xy 191.77 147.32) (xy 12.7 147.32)
		)
		(stroke
			(width 0)
			(type default)
		)
	)
	(wire
		(pts
			(xy 60.96 195.58) (xy 60.96 196.85)
		)
		(stroke
			(width 0)
			(type default)
		)
	)
	(wire
		(pts
			(xy 40.64 170.18) (xy 50.8 170.18)
		)
		(stroke
			(width 0)
			(type default)
		)
	)
	(wire
		(pts
			(xy 139.7 240.03) (xy 139.7 241.3)
		)
		(stroke
			(width 0)
			(type default)
		)
	)
	(wire
		(pts
			(xy 105.41 278.13) (xy 115.57 278.13)
		)
		(stroke
			(width 0)
			(type default)
		)
	)
	(wire
		(pts
			(xy 40.64 162.56) (xy 40.64 163.83)
		)
		(stroke
			(width 0)
			(type default)
		)
	)
	(wire
		(pts
			(xy 166.37 162.56) (xy 166.37 163.83)
		)
		(stroke
			(width 0)
			(type default)
		)
	)
	(wire
		(pts
			(xy 45.72 240.03) (xy 55.88 240.03)
		)
		(stroke
			(width 0)
			(type default)
		)
	)
	(wire
		(pts
			(xy 173.99 92.71) (xy 179.07 92.71)
		)
		(stroke
			(width 0)
			(type default)
		)
	)
	(wire
		(pts
			(xy 166.37 278.13) (xy 176.53 278.13)
		)
		(stroke
			(width 0)
			(type default)
		)
	)
	(polyline
		(pts
			(xy 39.37 229.87) (xy 39.37 255.27)
		)
		(stroke
			(width 0)
			(type default)
		)
	)
	(wire
		(pts
			(xy 146.05 170.18) (xy 156.21 170.18)
		)
		(stroke
			(width 0)
			(type default)
		)
	)
	(wire
		(pts
			(xy 111.76 214.63) (xy 121.92 214.63)
		)
		(stroke
			(width 0)
			(type default)
		)
	)
	(wire
		(pts
			(xy 78.74 240.03) (xy 88.9 240.03)
		)
		(stroke
			(width 0)
			(type default)
		)
	)
	(wire
		(pts
			(xy 99.06 240.03) (xy 99.06 241.3)
		)
		(stroke
			(width 0)
			(type default)
		)
	)
	(wire
		(pts
			(xy 34.29 224.79) (xy 34.29 223.52)
		)
		(stroke
			(width 0)
			(type default)
		)
	)
	(wire
		(pts
			(xy 91.44 220.98) (xy 91.44 222.25)
		)
		(stroke
			(width 0)
			(type default)
		)
	)
	(wire
		(pts
			(xy 191.77 82.55) (xy 194.31 82.55)
		)
		(stroke
			(width 0)
			(type default)
		)
	)
	(wire
		(pts
			(xy 34.29 199.39) (xy 34.29 198.12)
		)
		(stroke
			(width 0)
			(type default)
		)
	)
	(wire
		(pts
			(xy 86.36 195.58) (xy 86.36 196.85)
		)
		(stroke
			(width 0)
			(type default)
		)
	)
	(wire
		(pts
			(xy 121.92 214.63) (xy 121.92 215.9)
		)
		(stroke
			(width 0)
			(type default)
		)
	)
	(wire
		(pts
			(xy 152.4 223.52) (xy 162.56 223.52)
		)
		(stroke
			(width 0)
			(type default)
		)
	)
	(wire
		(pts
			(xy 227.33 77.47) (xy 229.87 77.47)
		)
		(stroke
			(width 0)
			(type default)
		)
	)
	(wire
		(pts
			(xy 139.7 195.58) (xy 139.7 196.85)
		)
		(stroke
			(width 0)
			(type default)
		)
	)
	(wire
		(pts
			(xy 156.21 168.91) (xy 156.21 170.18)
		)
		(stroke
			(width 0)
			(type default)
		)
	)
	(wire
		(pts
			(xy 191.77 77.47) (xy 194.31 77.47)
		)
		(stroke
			(width 0)
			(type default)
		)
	)
	(wire
		(pts
			(xy 106.68 189.23) (xy 106.68 190.5)
		)
		(stroke
			(width 0)
			(type default)
		)
	)
	(wire
		(pts
			(xy 60.96 220.98) (xy 60.96 222.25)
		)
		(stroke
			(width 0)
			(type default)
		)
	)
	(wire
		(pts
			(xy 20.32 161.29) (xy 20.32 162.56)
		)
		(stroke
			(width 0)
			(type default)
		)
	)
	(wire
		(pts
			(xy 172.72 187.96) (xy 172.72 189.23)
		)
		(stroke
			(width 0)
			(type default)
		)
	)
	(wire
		(pts
			(xy 227.33 85.09) (xy 246.38 85.09)
		)
		(stroke
			(width 0)
			(type default)
		)
	)
	(wire
		(pts
			(xy 95.25 162.56) (xy 105.41 162.56)
		)
		(stroke
			(width 0)
			(type default)
		)
	)
	(wire
		(pts
			(xy 88.9 247.65) (xy 99.06 247.65)
		)
		(stroke
			(width 0)
			(type default)
		)
	)
	(wire
		(pts
			(xy 152.4 215.9) (xy 152.4 217.17)
		)
		(stroke
			(width 0)
			(type default)
		)
	)
	(wire
		(pts
			(xy 60.96 189.23) (xy 60.96 190.5)
		)
		(stroke
			(width 0)
			(type default)
		)
	)
	(wire
		(pts
			(xy 30.48 162.56) (xy 30.48 163.83)
		)
		(stroke
			(width 0)
			(type default)
		)
	)
	(wire
		(pts
			(xy 30.48 168.91) (xy 30.48 170.18)
		)
		(stroke
			(width 0)
			(type default)
		)
	)
	(wire
		(pts
			(xy 176.53 276.86) (xy 176.53 278.13)
		)
		(stroke
			(width 0)
			(type default)
		)
	)
	(wire
		(pts
			(xy 152.4 247.65) (xy 162.56 247.65)
		)
		(stroke
			(width 0)
			(type default)
		)
	)
	(wire
		(pts
			(xy 242.57 100.33) (xy 242.57 99.06)
		)
		(stroke
			(width 0)
			(type default)
		)
	)
	(wire
		(pts
			(xy 24.13 223.52) (xy 34.29 223.52)
		)
		(stroke
			(width 0)
			(type default)
		)
	)
	(wire
		(pts
			(xy 60.96 196.85) (xy 71.12 196.85)
		)
		(stroke
			(width 0)
			(type default)
		)
	)
	(wire
		(pts
			(xy 162.56 246.38) (xy 162.56 247.65)
		)
		(stroke
			(width 0)
			(type default)
		)
	)
	(wire
		(pts
			(xy 24.13 190.5) (xy 34.29 190.5)
		)
		(stroke
			(width 0)
			(type default)
		)
	)
	(wire
		(pts
			(xy 71.12 195.58) (xy 71.12 196.85)
		)
		(stroke
			(width 0)
			(type default)
		)
	)
	(wire
		(pts
			(xy 105.41 269.24) (xy 105.41 270.51)
		)
		(stroke
			(width 0)
			(type default)
		)
	)
	(wire
		(pts
			(xy 111.76 220.98) (xy 111.76 222.25)
		)
		(stroke
			(width 0)
			(type default)
		)
	)
	(wire
		(pts
			(xy 182.88 240.03) (xy 182.88 241.3)
		)
		(stroke
			(width 0)
			(type default)
		)
	)
	(wire
		(pts
			(xy 176.53 279.4) (xy 176.53 278.13)
		)
		(stroke
			(width 0)
			(type default)
		)
	)
	(wire
		(pts
			(xy 146.05 162.56) (xy 156.21 162.56)
		)
		(stroke
			(width 0)
			(type default)
		)
	)
	(wire
		(pts
			(xy 129.54 240.03) (xy 139.7 240.03)
		)
		(stroke
			(width 0)
			(type default)
		)
	)
	(wire
		(pts
			(xy 24.13 215.9) (xy 24.13 217.17)
		)
		(stroke
			(width 0)
			(type default)
		)
	)
	(wire
		(pts
			(xy 166.37 170.18) (xy 176.53 170.18)
		)
		(stroke
			(width 0)
			(type default)
		)
	)
	(wire
		(pts
			(xy 125.73 168.91) (xy 125.73 170.18)
		)
		(stroke
			(width 0)
			(type default)
		)
	)
	(wire
		(pts
			(xy 20.32 240.03) (xy 20.32 241.3)
		)
		(stroke
			(width 0)
			(type default)
		)
	)
	(wire
		(pts
			(xy 59.69 189.23) (xy 60.96 189.23)
		)
		(stroke
			(width 0)
			(type default)
		)
	)
	(wire
		(pts
			(xy 162.56 247.65) (xy 172.72 247.65)
		)
		(stroke
			(width 0)
			(type default)
		)
	)
	(wire
		(pts
			(xy 152.4 238.76) (xy 152.4 240.03)
		)
		(stroke
			(width 0)
			(type default)
		)
	)
	(wire
		(pts
			(xy 246.38 83.82) (xy 246.38 85.09)
		)
		(stroke
			(width 0)
			(type default)
		)
	)
	(wire
		(pts
			(xy 119.38 195.58) (xy 119.38 196.85)
		)
		(stroke
			(width 0)
			(type default)
		)
	)
	(wire
		(pts
			(xy 115.57 168.91) (xy 115.57 170.18)
		)
		(stroke
			(width 0)
			(type default)
		)
	)
	(wire
		(pts
			(xy 191.77 74.93) (xy 194.31 74.93)
		)
		(stroke
			(width 0)
			(type default)
		)
	)
	(wire
		(pts
			(xy 60.96 214.63) (xy 71.12 214.63)
		)
		(stroke
			(width 0)
			(type default)
		)
	)
	(wire
		(pts
			(xy 139.7 248.92) (xy 139.7 247.65)
		)
		(stroke
			(width 0)
			(type default)
		)
	)
	(wire
		(pts
			(xy 109.22 247.65) (xy 119.38 247.65)
		)
		(stroke
			(width 0)
			(type default)
		)
	)
	(wire
		(pts
			(xy 172.72 222.25) (xy 172.72 223.52)
		)
		(stroke
			(width 0)
			(type default)
		)
	)
	(wire
		(pts
			(xy 20.32 162.56) (xy 20.32 163.83)
		)
		(stroke
			(width 0)
			(type default)
		)
	)
	(wire
		(pts
			(xy 50.8 170.18) (xy 60.96 170.18)
		)
		(stroke
			(width 0)
			(type default)
		)
	)
	(polyline
		(pts
			(xy 191.77 138.43) (xy 12.7 138.43)
		)
		(stroke
			(width 0)
			(type default)
		)
	)
	(wire
		(pts
			(xy 168.91 90.17) (xy 194.31 90.17)
		)
		(stroke
			(width 0)
			(type default)
		)
	)
	(wire
		(pts
			(xy 172.72 189.23) (xy 182.88 189.23)
		)
		(stroke
			(width 0)
			(type default)
		)
	)
	(wire
		(pts
			(xy 96.52 195.58) (xy 96.52 196.85)
		)
		(stroke
			(width 0)
			(type default)
		)
	)
	(wire
		(pts
			(xy 152.4 240.03) (xy 152.4 241.3)
		)
		(stroke
			(width 0)
			(type default)
		)
	)
	(wire
		(pts
			(xy 119.38 240.03) (xy 129.54 240.03)
		)
		(stroke
			(width 0)
			(type default)
		)
	)
	(wire
		(pts
			(xy 160.02 189.23) (xy 160.02 190.5)
		)
		(stroke
			(width 0)
			(type default)
		)
	)
	(wire
		(pts
			(xy 30.48 170.18) (xy 40.64 170.18)
		)
		(stroke
			(width 0)
			(type default)
		)
	)
	(wire
		(pts
			(xy 152.4 222.25) (xy 152.4 223.52)
		)
		(stroke
			(width 0)
			(type default)
		)
	)
	(wire
		(pts
			(xy 71.12 198.12) (xy 71.12 196.85)
		)
		(stroke
			(width 0)
			(type default)
		)
	)
	(wire
		(pts
			(xy 45.72 246.38) (xy 45.72 247.65)
		)
		(stroke
			(width 0)
			(type default)
		)
	)
	(wire
		(pts
			(xy 172.72 240.03) (xy 182.88 240.03)
		)
		(stroke
			(width 0)
			(type default)
		)
	)
	(wire
		(pts
			(xy 119.38 196.85) (xy 129.54 196.85)
		)
		(stroke
			(width 0)
			(type default)
		)
	)
	(polyline
		(pts
			(xy 49.53 179.07) (xy 49.53 229.87)
		)
		(stroke
			(width 0)
			(type default)
		)
	)
	(wire
		(pts
			(xy 115.57 162.56) (xy 115.57 163.83)
		)
		(stroke
			(width 0)
			(type default)
		)
	)
	(wire
		(pts
			(xy 95.25 170.18) (xy 105.41 170.18)
		)
		(stroke
			(width 0)
			(type default)
		)
	)
	(polyline
		(pts
			(xy 90.17 255.27) (xy 90.17 284.48)
		)
		(stroke
			(width 0)
			(type default)
		)
	)
	(wire
		(pts
			(xy 172.72 189.23) (xy 172.72 190.5)
		)
		(stroke
			(width 0)
			(type default)
		)
	)
	(wire
		(pts
			(xy 71.12 189.23) (xy 71.12 190.5)
		)
		(stroke
			(width 0)
			(type default)
		)
	)
	(wire
		(pts
			(xy 99.06 246.38) (xy 99.06 247.65)
		)
		(stroke
			(width 0)
			(type default)
		)
	)
	(wire
		(pts
			(xy 96.52 189.23) (xy 96.52 190.5)
		)
		(stroke
			(width 0)
			(type default)
		)
	)
	(wire
		(pts
			(xy 95.25 161.29) (xy 95.25 162.56)
		)
		(stroke
			(width 0)
			(type default)
		)
	)
	(wire
		(pts
			(xy 162.56 223.52) (xy 172.72 223.52)
		)
		(stroke
			(width 0)
			(type default)
		)
	)
	(wire
		(pts
			(xy 60.96 170.18) (xy 71.12 170.18)
		)
		(stroke
			(width 0)
			(type default)
		)
	)
	(wire
		(pts
			(xy 182.88 195.58) (xy 182.88 196.85)
		)
		(stroke
			(width 0)
			(type default)
		)
	)
	(wire
		(pts
			(xy 71.12 214.63) (xy 71.12 215.9)
		)
		(stroke
			(width 0)
			(type default)
		)
	)
	(wire
		(pts
			(xy 129.54 189.23) (xy 139.7 189.23)
		)
		(stroke
			(width 0)
			(type default)
		)
	)
	(wire
		(pts
			(xy 182.88 238.76) (xy 182.88 240.03)
		)
		(stroke
			(width 0)
			(type default)
		)
	)
	(wire
		(pts
			(xy 152.4 215.9) (xy 162.56 215.9)
		)
		(stroke
			(width 0)
			(type default)
		)
	)
	(wire
		(pts
			(xy 60.96 168.91) (xy 60.96 170.18)
		)
		(stroke
			(width 0)
			(type default)
		)
	)
	(wire
		(pts
			(xy 162.56 215.9) (xy 162.56 217.17)
		)
		(stroke
			(width 0)
			(type default)
		)
	)
	(wire
		(pts
			(xy 95.25 162.56) (xy 95.25 163.83)
		)
		(stroke
			(width 0)
			(type default)
		)
	)
	(wire
		(pts
			(xy 182.88 215.9) (xy 182.88 217.17)
		)
		(stroke
			(width 0)
			(type default)
		)
	)
	(wire
		(pts
			(xy 109.22 240.03) (xy 119.38 240.03)
		)
		(stroke
			(width 0)
			(type default)
		)
	)
	(wire
		(pts
			(xy 227.33 90.17) (xy 229.87 90.17)
		)
		(stroke
			(width 0)
			(type default)
		)
	)
	(wire
		(pts
			(xy 95.25 168.91) (xy 95.25 170.18)
		)
		(stroke
			(width 0)
			(type default)
		)
	)
	(wire
		(pts
			(xy 78.74 247.65) (xy 88.9 247.65)
		)
		(stroke
			(width 0)
			(type default)
		)
	)
	(wire
		(pts
			(xy 162.56 240.03) (xy 172.72 240.03)
		)
		(stroke
			(width 0)
			(type default)
		)
	)
	(wire
		(pts
			(xy 121.92 222.25) (xy 132.08 222.25)
		)
		(stroke
			(width 0)
			(type default)
		)
	)
	(polyline
		(pts
			(xy 12.7 204.47) (xy 191.77 204.47)
		)
		(stroke
			(width 0)
			(type default)
		)
	)
	(wire
		(pts
			(xy 135.89 168.91) (xy 135.89 170.18)
		)
		(stroke
			(width 0)
			(type default)
		)
	)
	(wire
		(pts
			(xy 60.96 162.56) (xy 71.12 162.56)
		)
		(stroke
			(width 0)
			(type default)
		)
	)
	(polyline
		(pts
			(xy 115.57 179.07) (xy 115.57 204.47)
		)
		(stroke
			(width 0)
			(type default)
		)
	)
	(wire
		(pts
			(xy 172.72 196.85) (xy 182.88 196.85)
		)
		(stroke
			(width 0)
			(type default)
		)
	)
	(wire
		(pts
			(xy 166.37 270.51) (xy 176.53 270.51)
		)
		(stroke
			(width 0)
			(type default)
		)
	)
	(wire
		(pts
			(xy 109.22 240.03) (xy 109.22 241.3)
		)
		(stroke
			(width 0)
			(type default)
		)
	)
	(polyline
		(pts
			(xy 82.55 147.32) (xy 82.55 229.87)
		)
		(stroke
			(width 0)
			(type default)
		)
	)
	(wire
		(pts
			(xy 172.72 215.9) (xy 182.88 215.9)
		)
		(stroke
			(width 0)
			(type default)
		)
	)
	(wire
		(pts
			(xy 146.05 168.91) (xy 146.05 170.18)
		)
		(stroke
			(width 0)
			(type default)
		)
	)
	(wire
		(pts
			(xy 105.41 170.18) (xy 115.57 170.18)
		)
		(stroke
			(width 0)
			(type default)
		)
	)
	(wire
		(pts
			(xy 146.05 270.51) (xy 146.05 271.78)
		)
		(stroke
			(width 0)
			(type default)
		)
	)
	(wire
		(pts
			(xy 168.91 87.63) (xy 176.53 87.63)
		)
		(stroke
			(width 0)
			(type default)
		)
	)
	(wire
		(pts
			(xy 135.89 270.51) (xy 146.05 270.51)
		)
		(stroke
			(width 0)
			(type default)
		)
	)
	(wire
		(pts
			(xy 91.44 222.25) (xy 101.6 222.25)
		)
		(stroke
			(width 0)
			(type default)
		)
	)
	(wire
		(pts
			(xy 172.72 247.65) (xy 182.88 247.65)
		)
		(stroke
			(width 0)
			(type default)
		)
	)
	(wire
		(pts
			(xy 146.05 276.86) (xy 146.05 278.13)
		)
		(stroke
			(width 0)
			(type default)
		)
	)
	(wire
		(pts
			(xy 162.56 240.03) (xy 162.56 241.3)
		)
		(stroke
			(width 0)
			(type default)
		)
	)
	(wire
		(pts
			(xy 88.9 240.03) (xy 88.9 241.3)
		)
		(stroke
			(width 0)
			(type default)
		)
	)
	(wire
		(pts
			(xy 132.08 223.52) (xy 132.08 222.25)
		)
		(stroke
			(width 0)
			(type default)
		)
	)
	(wire
		(pts
			(xy 115.57 279.4) (xy 115.57 278.13)
		)
		(stroke
			(width 0)
			(type default)
		)
	)
	(wire
		(pts
			(xy 101.6 214.63) (xy 111.76 214.63)
		)
		(stroke
			(width 0)
			(type default)
		)
	)
	(wire
		(pts
			(xy 129.54 189.23) (xy 129.54 190.5)
		)
		(stroke
			(width 0)
			(type default)
		)
	)
	(wire
		(pts
			(xy 34.29 196.85) (xy 34.29 198.12)
		)
		(stroke
			(width 0)
			(type default)
		)
	)
	(wire
		(pts
			(xy 152.4 214.63) (xy 152.4 215.9)
		)
		(stroke
			(width 0)
			(type default)
		)
	)
	(wire
		(pts
			(xy 172.72 246.38) (xy 172.72 247.65)
		)
		(stroke
			(width 0)
			(type default)
		)
	)
	(wire
		(pts
			(xy 40.64 168.91) (xy 40.64 170.18)
		)
		(stroke
			(width 0)
			(type default)
		)
	)
	(wire
		(pts
			(xy 78.74 238.76) (xy 78.74 240.03)
		)
		(stroke
			(width 0)
			(type default)
		)
	)
	(wire
		(pts
			(xy 50.8 162.56) (xy 50.8 163.83)
		)
		(stroke
			(width 0)
			(type default)
		)
	)
	(wire
		(pts
			(xy 78.74 240.03) (xy 78.74 241.3)
		)
		(stroke
			(width 0)
			(type default)
		)
	)
	(wire
		(pts
			(xy 121.92 220.98) (xy 121.92 222.25)
		)
		(stroke
			(width 0)
			(type default)
		)
	)
	(wire
		(pts
			(xy 106.68 198.12) (xy 106.68 196.85)
		)
		(stroke
			(width 0)
			(type default)
		)
	)
	(wire
		(pts
			(xy 115.57 270.51) (xy 115.57 271.78)
		)
		(stroke
			(width 0)
			(type default)
		)
	)
	(wire
		(pts
			(xy 121.92 214.63) (xy 132.08 214.63)
		)
		(stroke
			(width 0)
			(type default)
		)
	)
	(wire
		(pts
			(xy 172.72 215.9) (xy 172.72 217.17)
		)
		(stroke
			(width 0)
			(type default)
		)
	)
	(polyline
		(pts
			(xy 12.7 179.07) (xy 168.91 179.07)
		)
		(stroke
			(width 0)
			(type default)
		)
	)
	(wire
		(pts
			(xy 105.41 168.91) (xy 105.41 170.18)
		)
		(stroke
			(width 0)
			(type default)
		)
	)
	(wire
		(pts
			(xy 55.88 248.92) (xy 55.88 247.65)
		)
		(stroke
			(width 0)
			(type default)
		)
	)
	(wire
		(pts
			(xy 119.38 246.38) (xy 119.38 247.65)
		)
		(stroke
			(width 0)
			(type default)
		)
	)
	(wire
		(pts
			(xy 60.96 189.23) (xy 71.12 189.23)
		)
		(stroke
			(width 0)
			(type default)
		)
	)
	(wire
		(pts
			(xy 119.38 189.23) (xy 129.54 189.23)
		)
		(stroke
			(width 0)
			(type default)
		)
	)
	(wire
		(pts
			(xy 229.87 74.93) (xy 227.33 74.93)
		)
		(stroke
			(width 0)
			(type default)
		)
	)
	(wire
		(pts
			(xy 227.33 80.01) (xy 229.87 80.01)
		)
		(stroke
			(width 0)
			(type default)
		)
	)
	(wire
		(pts
			(xy 193.04 96.52) (xy 193.04 95.25)
		)
		(stroke
			(width 0)
			(type default)
		)
	)
	(wire
		(pts
			(xy 24.13 214.63) (xy 24.13 215.9)
		)
		(stroke
			(width 0)
			(type default)
		)
	)
	(wire
		(pts
			(xy 109.22 246.38) (xy 109.22 247.65)
		)
		(stroke
			(width 0)
			(type default)
		)
	)
	(wire
		(pts
			(xy 88.9 246.38) (xy 88.9 247.65)
		)
		(stroke
			(width 0)
			(type default)
		)
	)
	(wire
		(pts
			(xy 146.05 162.56) (xy 146.05 163.83)
		)
		(stroke
			(width 0)
			(type default)
		)
	)
	(wire
		(pts
			(xy 45.72 240.03) (xy 45.72 241.3)
		)
		(stroke
			(width 0)
			(type default)
		)
	)
	(wire
		(pts
			(xy 179.07 96.52) (xy 179.07 92.71)
		)
		(stroke
			(width 0)
			(type default)
		)
	)
	(wire
		(pts
			(xy 24.13 215.9) (xy 34.29 215.9)
		)
		(stroke
			(width 0)
			(type default)
		)
	)
	(wire
		(pts
			(xy 119.38 187.96) (xy 119.38 189.23)
		)
		(stroke
			(width 0)
			(type default)
		)
	)
	(wire
		(pts
			(xy 229.87 87.63) (xy 227.33 87.63)
		)
		(stroke
			(width 0)
			(type default)
		)
	)
	(wire
		(pts
			(xy 30.48 240.03) (xy 20.32 240.03)
		)
		(stroke
			(width 0)
			(type default)
		)
	)
	(wire
		(pts
			(xy 99.06 247.65) (xy 109.22 247.65)
		)
		(stroke
			(width 0)
			(type default)
		)
	)
	(wire
		(pts
			(xy 182.88 198.12) (xy 182.88 196.85)
		)
		(stroke
			(width 0)
			(type default)
		)
	)
	(wire
		(pts
			(xy 176.53 271.78) (xy 176.53 270.51)
		)
		(stroke
			(width 0)
			(type default)
		)
	)
	(wire
		(pts
			(xy 91.44 214.63) (xy 91.44 215.9)
		)
		(stroke
			(width 0)
			(type default)
		)
	)
	(wire
		(pts
			(xy 129.54 246.38) (xy 129.54 247.65)
		)
		(stroke
			(width 0)
			(type default)
		)
	)
	(wire
		(pts
			(xy 34.29 222.25) (xy 34.29 223.52)
		)
		(stroke
			(width 0)
			(type default)
		)
	)
	(wire
		(pts
			(xy 156.21 170.18) (xy 166.37 170.18)
		)
		(stroke
			(width 0)
			(type default)
		)
	)
	(wire
		(pts
			(xy 139.7 196.85) (xy 149.86 196.85)
		)
		(stroke
			(width 0)
			(type default)
		)
	)
	(wire
		(pts
			(xy 149.86 189.23) (xy 149.86 190.5)
		)
		(stroke
			(width 0)
			(type default)
		)
	)
	(wire
		(pts
			(xy 60.96 162.56) (xy 60.96 163.83)
		)
		(stroke
			(width 0)
			(type default)
		)
	)
	(wire
		(pts
			(xy 86.36 187.96) (xy 86.36 189.23)
		)
		(stroke
			(width 0)
			(type default)
		)
	)
	(wire
		(pts
			(xy 149.86 189.23) (xy 160.02 189.23)
		)
		(stroke
			(width 0)
			(type default)
		)
	)
	(wire
		(pts
			(xy 119.38 247.65) (xy 129.54 247.65)
		)
		(stroke
			(width 0)
			(type default)
		)
	)
	(wire
		(pts
			(xy 34.29 215.9) (xy 34.29 217.17)
		)
		(stroke
			(width 0)
			(type default)
		)
	)
	(wire
		(pts
			(xy 166.37 276.86) (xy 166.37 278.13)
		)
		(stroke
			(width 0)
			(type default)
		)
	)
	(wire
		(pts
			(xy 71.12 168.91) (xy 71.12 170.18)
		)
		(stroke
			(width 0)
			(type default)
		)
	)
	(wire
		(pts
			(xy 182.88 248.92) (xy 182.88 247.65)
		)
		(stroke
			(width 0)
			(type default)
		)
	)
	(label "XCVR_VREF"
		(at 30.48 240.03 180)
		(effects
			(font
				(size 1.27 1.27)
			)
			(justify right bottom)
		)
	)
	(label "XCVR_VREF"
		(at 248.92 92.71 180)
		(effects
			(font
				(size 1.27 1.27)
			)
			(justify right bottom)
		)
	)
	(global_label "SD_VDD_AUX"
		(shape input)
		(at 173.99 92.71 180)
		(fields_autoplaced yes)
		(effects
			(font
				(size 1.27 1.27)
			)
			(justify right)
		)
		(property "Intersheetrefs" "${INTERSHEET_REFS}"
			(at 159.3329 92.71 0)
			(effects
				(font
					(size 1.27 1.27)
				)
				(justify right)
			)
		)
	)
	(global_label "SD_VDD"
		(shape input)
		(at 248.92 85.09 0)
		(fields_autoplaced yes)
		(effects
			(font
				(size 1.27 1.27)
			)
			(justify left)
		)
		(property "Intersheetrefs" "${INTERSHEET_REFS}"
			(at 258.9809 85.09 0)
			(effects
				(font
					(size 1.27 1.27)
				)
				(justify left)
			)
		)
	)
	(global_label "SD_VDD"
		(shape input)
		(at 59.69 189.23 180)
		(fields_autoplaced yes)
		(effects
			(font
				(size 1.27 1.27)
			)
			(justify right)
		)
		(property "Intersheetrefs" "${INTERSHEET_REFS}"
			(at 49.6291 189.23 0)
			(effects
				(font
					(size 1.27 1.27)
				)
				(justify right)
			)
		)
	)
	(symbol
		(lib_id "antmicroCapacitors0402:C_1n_0402")
		(at 152.4 246.38 90)
		(unit 1)
		(exclude_from_sim no)
		(in_bom yes)
		(on_board yes)
		(dnp no)
		(fields_autoplaced yes)
		(property "Reference" "C52"
			(at 154.94 242.5636 90)
			(effects
				(font
					(size 1.27 1.27)
					(thickness 0.15)
				)
				(justify right)
			)
		)
		(property "Value" "C_1n_0402"
			(at 162.56 226.06 0)
			(effects
				(font
					(size 1.27 1.27)
					(thickness 0.15)
				)
				(justify left bottom)
				(hide yes)
			)
		)
		(property "Footprint" "antmicro-footprints:C_0402_1005Metric"
			(at 165.1 226.06 0)
			(effects
				(font
					(size 1.27 1.27)
					(thickness 0.15)
				)
				(justify left bottom)
				(hide yes)
			)
		)
		(property "Datasheet" "https://www.murata.com/products/productdetail?partno=GRM1555C1H102JA01%23"
			(at 167.64 226.06 0)
			(effects
				(font
					(size 1.27 1.27)
					(thickness 0.15)
				)
				(justify left bottom)
				(hide yes)
			)
		)
		(property "Description" "SMD Multilayer Ceramic Capacitor, 1000 pF, 50 V, 0402 [1005 Metric], ± 5%, C0G / NP0, GRM Series"
			(at 152.4 246.38 0)
			(effects
				(font
					(size 1.27 1.27)
				)
				(hide yes)
			)
		)
		(property "MPN" "GRM1555C1H102JA01D"
			(at 170.18 226.06 0)
			(effects
				(font
					(size 1.27 1.27)
					(thickness 0.15)
				)
				(justify left bottom)
				(hide yes)
			)
		)
		(property "Manufacturer" "Murata"
			(at 172.72 226.06 0)
			(effects
				(font
					(size 1.27 1.27)
					(thickness 0.15)
				)
				(justify left bottom)
				(hide yes)
			)
		)
		(property "License" "Apache-2.0"
			(at 175.26 226.06 0)
			(effects
				(font
					(size 1.27 1.27)
					(thickness 0.15)
				)
				(justify left bottom)
				(hide yes)
			)
		)
		(property "Author" "Antmicro"
			(at 177.8 226.06 0)
			(effects
				(font
					(size 1.27 1.27)
					(thickness 0.15)
				)
				(justify left bottom)
				(hide yes)
			)
		)
		(property "Val" "1n"
			(at 154.94 245.1036 90)
			(effects
				(font
					(size 1.27 1.27)
					(thickness 0.15)
				)
				(justify right)
			)
		)
		(property "Voltage" "50V"
			(at 180.34 226.06 0)
			(effects
				(font
					(size 1.27 1.27)
				)
				(justify left bottom)
				(hide yes)
			)
		)
		(property "Dielectric" "C0G"
			(at 182.88 226.06 0)
			(effects
				(font
					(size 1.27 1.27)
				)
				(justify left bottom)
				(hide yes)
			)
		)
		(property "Public" ""
			(at 185.42 226.06 0)
			(effects
				(font
					(size 1.27 1.27)
				)
				(justify left bottom)
				(hide yes)
			)
		)
		(pin "1"
		)
		(pin "2"
		)
		(instances
			(project "polarfire-som"
				(path ""
					(reference "C52")
					(unit 1)
				)
			)
		)
	)
	(symbol
		(lib_id "antmicropower:VDDAUX")
		(at 105.41 269.24 0)
		(unit 1)
		(exclude_from_sim no)
		(in_bom yes)
		(on_board yes)
		(dnp no)
		(property "Reference" "#PWR0327"
			(at 105.41 273.05 0)
			(effects
				(font
					(size 1.27 1.27)
				)
				(hide yes)
			)
		)
		(property "Value" "VDDAUX"
			(at 105.41 265.43 0)
			(effects
				(font
					(size 1.27 1.27)
				)
			)
		)
		(property "Footprint" ""
			(at 105.41 269.24 0)
			(effects
				(font
					(size 1.27 1.27)
				)
				(hide yes)
			)
		)
		(property "Datasheet" ""
			(at 105.41 269.24 0)
			(effects
				(font
					(size 1.27 1.27)
				)
				(hide yes)
			)
		)
		(property "Description" ""
			(at 105.41 269.24 0)
			(effects
				(font
					(size 1.27 1.27)
				)
				(hide yes)
			)
		)
		(pin "1"
		)
		(instances
			(project "polarfire-som"
				(path ""
					(reference "#PWR0327")
					(unit 1)
				)
			)
		)
	)
	(symbol
		(lib_id "antmicropower:+2V5")
		(at 191.77 85.09 90)
		(unit 1)
		(exclude_from_sim no)
		(in_bom yes)
		(on_board yes)
		(dnp no)
		(property "Reference" "#PWR039"
			(at 195.58 85.09 0)
			(effects
				(font
					(size 1.27 1.27)
				)
				(hide yes)
			)
		)
		(property "Value" "+2V5"
			(at 186.055 85.09 90)
			(effects
				(font
					(size 1.27 1.27)
				)
			)
		)
		(property "Footprint" ""
			(at 191.77 85.09 0)
			(effects
				(font
					(size 1.27 1.27)
				)
				(hide yes)
			)
		)
		(property "Datasheet" ""
			(at 191.77 85.09 0)
			(effects
				(font
					(size 1.27 1.27)
				)
				(hide yes)
			)
		)
		(property "Description" ""
			(at 191.77 85.09 0)
			(effects
				(font
					(size 1.27 1.27)
				)
				(hide yes)
			)
		)
		(pin "1"
		)
		(instances
			(project "polarfire-som"
				(path ""
					(reference "#PWR039")
					(unit 1)
				)
			)
		)
	)
	(symbol
		(lib_id "antmicroCapacitors0402:C_10n_0402")
		(at 115.57 168.91 90)
		(unit 1)
		(exclude_from_sim no)
		(in_bom yes)
		(on_board yes)
		(dnp no)
		(fields_autoplaced yes)
		(property "Reference" "C55"
			(at 118.11 165.0936 90)
			(effects
				(font
					(size 1.27 1.27)
					(thickness 0.15)
				)
				(justify right)
			)
		)
		(property "Value" "C_10n_0402"
			(at 125.73 148.59 0)
			(effects
				(font
					(size 1.27 1.27)
					(thickness 0.15)
				)
				(justify left bottom)
				(hide yes)
			)
		)
		(property "Footprint" "antmicro-footprints:C_0402_1005Metric"
			(at 128.27 148.59 0)
			(effects
				(font
					(size 1.27 1.27)
					(thickness 0.15)
				)
				(justify left bottom)
				(hide yes)
			)
		)
		(property "Datasheet" "https://www.murata.com/products/productdetail?partno=GRM155R71H103KA88%23"
			(at 130.81 148.59 0)
			(effects
				(font
					(size 1.27 1.27)
					(thickness 0.15)
				)
				(justify left bottom)
				(hide yes)
			)
		)
		(property "Description" "SMD Multilayer Ceramic Capacitor, 10000 pF, 50 V, 0402 [1005 Metric], ± 10%, X7R, GRM Series"
			(at 115.57 168.91 0)
			(effects
				(font
					(size 1.27 1.27)
				)
				(hide yes)
			)
		)
		(property "MPN" "GRM155R71H103KA88D"
			(at 133.35 148.59 0)
			(effects
				(font
					(size 1.27 1.27)
					(thickness 0.15)
				)
				(justify left bottom)
				(hide yes)
			)
		)
		(property "Manufacturer" "Murata"
			(at 135.89 148.59 0)
			(effects
				(font
					(size 1.27 1.27)
					(thickness 0.15)
				)
				(justify left bottom)
				(hide yes)
			)
		)
		(property "License" "Apache-2.0"
			(at 138.43 148.59 0)
			(effects
				(font
					(size 1.27 1.27)
					(thickness 0.15)
				)
				(justify left bottom)
				(hide yes)
			)
		)
		(property "Author" "Antmicro"
			(at 140.97 148.59 0)
			(effects
				(font
					(size 1.27 1.27)
					(thickness 0.15)
				)
				(justify left bottom)
				(hide yes)
			)
		)
		(property "Val" "10n"
			(at 118.11 167.6336 90)
			(effects
				(font
					(size 1.27 1.27)
					(thickness 0.15)
				)
				(justify right)
			)
		)
		(property "Voltage" "50V"
			(at 143.51 148.59 0)
			(effects
				(font
					(size 1.27 1.27)
				)
				(justify left bottom)
				(hide yes)
			)
		)
		(property "Dielectric" "X7R"
			(at 146.05 148.59 0)
			(effects
				(font
					(size 1.27 1.27)
				)
				(justify left bottom)
				(hide yes)
			)
		)
		(property "Public" ""
			(at 148.59 148.59 0)
			(effects
				(font
					(size 1.27 1.27)
				)
				(justify left bottom)
				(hide yes)
			)
		)
		(pin "1"
		)
		(pin "2"
		)
		(instances
			(project "polarfire-som"
				(path ""
					(reference "C55")
					(unit 1)
				)
			)
		)
	)
	(symbol
		(lib_id "antmicroCapacitors0603:C_47u_0603")
		(at 160.02 195.58 90)
		(unit 1)
		(exclude_from_sim no)
		(in_bom yes)
		(on_board yes)
		(dnp no)
		(fields_autoplaced yes)
		(property "Reference" "C54"
			(at 162.56 191.7636 90)
			(effects
				(font
					(size 1.27 1.27)
					(thickness 0.15)
				)
				(justify right)
			)
		)
		(property "Value" "C_47u_0603"
			(at 170.18 175.26 0)
			(effects
				(font
					(size 1.27 1.27)
					(thickness 0.15)
				)
				(justify left bottom)
				(hide yes)
			)
		)
		(property "Footprint" "antmicro-footprints:C_0603_1608Metric"
			(at 172.72 175.26 0)
			(effects
				(font
					(size 1.27 1.27)
					(thickness 0.15)
				)
				(justify left bottom)
				(hide yes)
			)
		)
		(property "Datasheet" "https://www.murata.com/products/productdetail?partno=GRM188R60J476ME15%23"
			(at 175.26 175.26 0)
			(effects
				(font
					(size 1.27 1.27)
					(thickness 0.15)
				)
				(justify left bottom)
				(hide yes)
			)
		)
		(property "Description" "SMD Multilayer Ceramic Capacitor, 47 µF, 6.3 V, 0603 [1608 Metric], ± 20%, X5R, GRM Series"
			(at 160.02 195.58 0)
			(effects
				(font
					(size 1.27 1.27)
				)
				(hide yes)
			)
		)
		(property "MPN" "GRM188R60J476ME15D"
			(at 177.8 175.26 0)
			(effects
				(font
					(size 1.27 1.27)
					(thickness 0.15)
				)
				(justify left bottom)
				(hide yes)
			)
		)
		(property "Manufacturer" "Murata"
			(at 180.34 175.26 0)
			(effects
				(font
					(size 1.27 1.27)
					(thickness 0.15)
				)
				(justify left bottom)
				(hide yes)
			)
		)
		(property "License" "Apache-2.0"
			(at 182.88 175.26 0)
			(effects
				(font
					(size 1.27 1.27)
					(thickness 0.15)
				)
				(justify left bottom)
				(hide yes)
			)
		)
		(property "Author" "Antmicro"
			(at 185.42 175.26 0)
			(effects
				(font
					(size 1.27 1.27)
					(thickness 0.15)
				)
				(justify left bottom)
				(hide yes)
			)
		)
		(property "Val" "47u"
			(at 162.56 194.3036 90)
			(effects
				(font
					(size 1.27 1.27)
					(thickness 0.15)
				)
				(justify right)
			)
		)
		(property "Voltage" "50V"
			(at 187.96 175.26 0)
			(effects
				(font
					(size 1.27 1.27)
				)
				(justify left bottom)
				(hide yes)
			)
		)
		(property "Dielectric" "X7R"
			(at 190.5 175.26 0)
			(effects
				(font
					(size 1.27 1.27)
				)
				(justify left bottom)
				(hide yes)
			)
		)
		(property "Capacitance" "47u"
			(at 162.56 194.31 90)
			(effects
				(font
					(size 1.27 1.27)
				)
				(justify right)
				(hide yes)
			)
		)
		(property "Public" ""
			(at 193.04 175.26 0)
			(effects
				(font
					(size 1.27 1.27)
				)
				(justify left bottom)
				(hide yes)
			)
		)
		(pin "1"
		)
		(pin "2"
		)
		(instances
			(project "polarfire-som"
				(path ""
					(reference "C54")
					(unit 1)
				)
			)
		)
	)
	(symbol
		(lib_id "antmicropower:GND")
		(at 71.12 171.45 0)
		(unit 1)
		(exclude_from_sim no)
		(in_bom yes)
		(on_board yes)
		(dnp no)
		(property "Reference" "#PWR016"
			(at 80.01 173.99 0)
			(effects
				(font
					(size 1.27 1.27)
					(thickness 0.15)
				)
				(justify left bottom)
				(hide yes)
			)
		)
		(property "Value" "GND"
			(at 71.12 175.26 0)
			(effects
				(font
					(size 1.27 1.27)
					(thickness 0.15)
				)
			)
		)
		(property "Footprint" ""
			(at 80.01 179.07 0)
			(effects
				(font
					(size 1.27 1.27)
					(thickness 0.15)
				)
				(justify left bottom)
				(hide yes)
			)
		)
		(property "Datasheet" ""
			(at 80.01 184.15 0)
			(effects
				(font
					(size 1.27 1.27)
					(thickness 0.15)
				)
				(justify left bottom)
				(hide yes)
			)
		)
		(property "Description" ""
			(at 71.12 171.45 0)
			(effects
				(font
					(size 1.27 1.27)
				)
				(hide yes)
			)
		)
		(property "Author" "Antmicro"
			(at 80.01 179.07 0)
			(effects
				(font
					(size 1.27 1.27)
					(thickness 0.15)
				)
				(justify left bottom)
				(hide yes)
			)
		)
		(property "License" "Apache-2.0"
			(at 80.01 181.61 0)
			(effects
				(font
					(size 1.27 1.27)
					(thickness 0.15)
				)
				(justify left bottom)
				(hide yes)
			)
		)
		(pin "1"
		)
		(instances
			(project "polarfire-som"
				(path ""
					(reference "#PWR016")
					(unit 1)
				)
			)
		)
	)
	(symbol
		(lib_id "antmicropower:GND")
		(at 160.02 196.85 0)
		(unit 1)
		(exclude_from_sim no)
		(in_bom yes)
		(on_board yes)
		(dnp no)
		(property "Reference" "#PWR028"
			(at 168.91 199.39 0)
			(effects
				(font
					(size 1.27 1.27)
					(thickness 0.15)
				)
				(justify left bottom)
				(hide yes)
			)
		)
		(property "Value" "GND"
			(at 160.02 200.66 0)
			(effects
				(font
					(size 1.27 1.27)
					(thickness 0.15)
				)
			)
		)
		(property "Footprint" ""
			(at 168.91 204.47 0)
			(effects
				(font
					(size 1.27 1.27)
					(thickness 0.15)
				)
				(justify left bottom)
				(hide yes)
			)
		)
		(property "Datasheet" ""
			(at 168.91 209.55 0)
			(effects
				(font
					(size 1.27 1.27)
					(thickness 0.15)
				)
				(justify left bottom)
				(hide yes)
			)
		)
		(property "Description" ""
			(at 160.02 196.85 0)
			(effects
				(font
					(size 1.27 1.27)
				)
				(hide yes)
			)
		)
		(property "Author" "Antmicro"
			(at 168.91 204.47 0)
			(effects
				(font
					(size 1.27 1.27)
					(thickness 0.15)
				)
				(justify left bottom)
				(hide yes)
			)
		)
		(property "License" "Apache-2.0"
			(at 168.91 207.01 0)
			(effects
				(font
					(size 1.27 1.27)
					(thickness 0.15)
				)
				(justify left bottom)
				(hide yes)
			)
		)
		(pin "1"
		)
		(instances
			(project "polarfire-som"
				(path ""
					(reference "#PWR028")
					(unit 1)
				)
			)
		)
	)
	(symbol
		(lib_id "antmicroFPGAChips:MPFS250T-FCVG484E")
		(at 194.31 74.93 0)
		(unit 9)
		(exclude_from_sim no)
		(in_bom yes)
		(on_board yes)
		(dnp no)
		(fields_autoplaced yes)
		(property "Reference" "U1"
			(at 210.82 67.31 0)
			(effects
				(font
					(size 1.27 1.27)
					(thickness 0.15)
				)
			)
		)
		(property "Value" "MPFS250T-FCVG484"
			(at 299.72 80.01 0)
			(effects
				(font
					(size 1.27 1.27)
					(thickness 0.15)
				)
				(justify left bottom)
				(hide yes)
			)
		)
		(property "Footprint" "antmicro-footprints:BGA-484_19x19mm_Layout22x22_P0.8mm_FCVG484"
			(at 299.72 82.55 0)
			(effects
				(font
					(size 1.27 1.27)
					(thickness 0.15)
				)
				(justify left bottom)
				(hide yes)
			)
		)
		(property "Datasheet" "https://ww1.microchip.com/downloads/aemDocuments/documents/FPGA/ProductDocuments/DataSheets/PolarFire-SoC-Datasheet-DS00004248.pdf"
			(at 299.72 85.09 0)
			(effects
				(font
					(size 1.27 1.27)
					(thickness 0.15)
				)
				(justify left bottom)
				(hide yes)
			)
		)
		(property "Description" "RISC-V System On Chip (SOC) IC PolarFire® FPGA - 254K Logic Modules 484-FCBGA (19x19)"
			(at 299.72 95.25 0)
			(effects
				(font
					(size 1.27 1.27)
				)
				(justify left bottom)
				(hide yes)
			)
		)
		(property "MPN" "MPFS250T-FCVG484E"
			(at 210.82 69.85 0)
			(effects
				(font
					(size 1.27 1.27)
					(thickness 0.15)
				)
			)
		)
		(property "Manufacturer" "Microchip Technology"
			(at 299.72 87.63 0)
			(effects
				(font
					(size 1.27 1.27)
					(thickness 0.15)
				)
				(justify left bottom)
				(hide yes)
			)
		)
		(property "VSD_class" "MPFS250T"
			(at 298.45 92.71 0)
			(effects
				(font
					(size 1.27 1.27)
					(thickness 0.15)
				)
				(justify left bottom)
				(hide yes)
			)
		)
		(property "Author" "Antmicro"
			(at 299.72 90.17 0)
			(effects
				(font
					(size 1.27 1.27)
					(thickness 0.15)
				)
				(justify left bottom)
				(hide yes)
			)
		)
		(property "License" "Apache-2.0"
			(at 299.72 92.71 0)
			(effects
				(font
					(size 1.27 1.27)
					(thickness 0.15)
				)
				(justify left bottom)
				(hide yes)
			)
		)
		(pin "AA12"
		)
		(pin "AA13"
		)
		(pin "AA15"
		)
		(pin "AA16"
		)
		(pin "AA17"
		)
		(pin "AA18"
		)
		(pin "AA20"
		)
		(pin "AA21"
		)
		(pin "AA22"
		)
		(pin "AB12"
		)
		(pin "AB13"
		)
		(pin "AB14"
		)
		(pin "AB15"
		)
		(pin "AB17"
		)
		(pin "AB18"
		)
		(pin "AB19"
		)
		(pin "AB20"
		)
		(pin "AB21"
		)
		(pin "R12"
		)
		(pin "R14"
		)
		(pin "R15"
		)
		(pin "R16"
		)
		(pin "T12"
		)
		(pin "T13"
		)
		(pin "T15"
		)
		(pin "T16"
		)
		(pin "T17"
		)
		(pin "U12"
		)
		(pin "U13"
		)
		(pin "U14"
		)
		(pin "U15"
		)
		(pin "U17"
		)
		(pin "U18"
		)
		(pin "U19"
		)
		(pin "V12"
		)
		(pin "V14"
		)
		(pin "V15"
		)
		(pin "V16"
		)
		(pin "V17"
		)
		(pin "V19"
		)
		(pin "V20"
		)
		(pin "V21"
		)
		(pin "V22"
		)
		(pin "W12"
		)
		(pin "W13"
		)
		(pin "W14"
		)
		(pin "W16"
		)
		(pin "W17"
		)
		(pin "W18"
		)
		(pin "W19"
		)
		(pin "W21"
		)
		(pin "W22"
		)
		(pin "Y13"
		)
		(pin "Y14"
		)
		(pin "Y15"
		)
		(pin "Y16"
		)
		(pin "Y18"
		)
		(pin "Y19"
		)
		(pin "Y20"
		)
		(pin "Y21"
		)
		(pin "A10"
		)
		(pin "A11"
		)
		(pin "A12"
		)
		(pin "A13"
		)
		(pin "A15"
		)
		(pin "A16"
		)
		(pin "A17"
		)
		(pin "A18"
		)
		(pin "A20"
		)
		(pin "A21"
		)
		(pin "A5"
		)
		(pin "A6"
		)
		(pin "A7"
		)
		(pin "A8"
		)
		(pin "B10"
		)
		(pin "B12"
		)
		(pin "B13"
		)
		(pin "B14"
		)
		(pin "B15"
		)
		(pin "B17"
		)
		(pin "B18"
		)
		(pin "B19"
		)
		(pin "B20"
		)
		(pin "B21"
		)
		(pin "B22"
		)
		(pin "B4"
		)
		(pin "B5"
		)
		(pin "B7"
		)
		(pin "B8"
		)
		(pin "B9"
		)
		(pin "C10"
		)
		(pin "C11"
		)
		(pin "C12"
		)
		(pin "C14"
		)
		(pin "C15"
		)
		(pin "C16"
		)
		(pin "C17"
		)
		(pin "C19"
		)
		(pin "C20"
		)
		(pin "C22"
		)
		(pin "C4"
		)
		(pin "C5"
		)
		(pin "C6"
		)
		(pin "C7"
		)
		(pin "C9"
		)
		(pin "D11"
		)
		(pin "D12"
		)
		(pin "D13"
		)
		(pin "D14"
		)
		(pin "D16"
		)
		(pin "D17"
		)
		(pin "D18"
		)
		(pin "D19"
		)
		(pin "D20"
		)
		(pin "D21"
		)
		(pin "D22"
		)
		(pin "D6"
		)
		(pin "D7"
		)
		(pin "D8"
		)
		(pin "D9"
		)
		(pin "E10"
		)
		(pin "E11"
		)
		(pin "E13"
		)
		(pin "E14"
		)
		(pin "E15"
		)
		(pin "E16"
		)
		(pin "E18"
		)
		(pin "E19"
		)
		(pin "F10"
		)
		(pin "F11"
		)
		(pin "F12"
		)
		(pin "F13"
		)
		(pin "F15"
		)
		(pin "F16"
		)
		(pin "F17"
		)
		(pin "G12"
		)
		(pin "G13"
		)
		(pin "G14"
		)
		(pin "G15"
		)
		(pin "G17"
		)
		(pin "H12"
		)
		(pin "H13"
		)
		(pin "H15"
		)
		(pin "H17"
		)
		(pin "A2"
		)
		(pin "A3"
		)
		(pin "B1"
		)
		(pin "B2"
		)
		(pin "B3"
		)
		(pin "C1"
		)
		(pin "C2"
		)
		(pin "D1"
		)
		(pin "D2"
		)
		(pin "D3"
		)
		(pin "D4"
		)
		(pin "E1"
		)
		(pin "E3"
		)
		(pin "E4"
		)
		(pin "E5"
		)
		(pin "F1"
		)
		(pin "F2"
		)
		(pin "F3"
		)
		(pin "F5"
		)
		(pin "F6"
		)
		(pin "G2"
		)
		(pin "G3"
		)
		(pin "G4"
		)
		(pin "G5"
		)
		(pin "E6"
		)
		(pin "E8"
		)
		(pin "E9"
		)
		(pin "F7"
		)
		(pin "F8"
		)
		(pin "G10"
		)
		(pin "G7"
		)
		(pin "G8"
		)
		(pin "G9"
		)
		(pin "H10"
		)
		(pin "H11"
		)
		(pin "H7"
		)
		(pin "H9"
		)
		(pin "H1"
		)
		(pin "H2"
		)
		(pin "H4"
		)
		(pin "H5"
		)
		(pin "H6"
		)
		(pin "J1"
		)
		(pin "J2"
		)
		(pin "J3"
		)
		(pin "J4"
		)
		(pin "J6"
		)
		(pin "J7"
		)
		(pin "K3"
		)
		(pin "K4"
		)
		(pin "K5"
		)
		(pin "K6"
		)
		(pin "K7"
		)
		(pin "L5"
		)
		(pin "L6"
		)
		(pin "L7"
		)
		(pin "L8"
		)
		(pin "M7"
		)
		(pin "N6"
		)
		(pin "N7"
		)
		(pin "N8"
		)
		(pin "AA1"
		)
		(pin "AA10"
		)
		(pin "AA11"
		)
		(pin "AA2"
		)
		(pin "AA3"
		)
		(pin "AA5"
		)
		(pin "AA6"
		)
		(pin "AA7"
		)
		(pin "AA8"
		)
		(pin "AB10"
		)
		(pin "AB2"
		)
		(pin "AB3"
		)
		(pin "AB4"
		)
		(pin "AB5"
		)
		(pin "AB7"
		)
		(pin "AB8"
		)
		(pin "AB9"
		)
		(pin "K1"
		)
		(pin "L1"
		)
		(pin "L2"
		)
		(pin "L3"
		)
		(pin "M2"
		)
		(pin "M3"
		)
		(pin "M4"
		)
		(pin "M5"
		)
		(pin "N1"
		)
		(pin "N2"
		)
		(pin "N4"
		)
		(pin "N5"
		)
		(pin "P1"
		)
		(pin "P2"
		)
		(pin "P3"
		)
		(pin "P4"
		)
		(pin "P6"
		)
		(pin "P7"
		)
		(pin "P8"
		)
		(pin "R1"
		)
		(pin "R10"
		)
		(pin "R11"
		)
		(pin "R3"
		)
		(pin "R4"
		)
		(pin "R5"
		)
		(pin "R6"
		)
		(pin "R8"
		)
		(pin "T1"
		)
		(pin "T10"
		)
		(pin "T11"
		)
		(pin "T2"
		)
		(pin "T3"
		)
		(pin "T5"
		)
		(pin "T6"
		)
		(pin "T7"
		)
		(pin "T8"
		)
		(pin "U10"
		)
		(pin "U2"
		)
		(pin "U3"
		)
		(pin "U4"
		)
		(pin "U5"
		)
		(pin "U7"
		)
		(pin "U8"
		)
		(pin "U9"
		)
		(pin "V1"
		)
		(pin "V10"
		)
		(pin "V11"
		)
		(pin "V2"
		)
		(pin "V4"
		)
		(pin "V5"
		)
		(pin "V6"
		)
		(pin "V7"
		)
		(pin "V9"
		)
		(pin "W1"
		)
		(pin "W11"
		)
		(pin "W2"
		)
		(pin "W3"
		)
		(pin "W4"
		)
		(pin "W6"
		)
		(pin "W7"
		)
		(pin "W8"
		)
		(pin "W9"
		)
		(pin "Y1"
		)
		(pin "Y10"
		)
		(pin "Y11"
		)
		(pin "Y3"
		)
		(pin "Y4"
		)
		(pin "Y5"
		)
		(pin "Y6"
		)
		(pin "Y8"
		)
		(pin "Y9"
		)
		(pin "F21"
		)
		(pin "F22"
		)
		(pin "G19"
		)
		(pin "G20"
		)
		(pin "H21"
		)
		(pin "H22"
		)
		(pin "J19"
		)
		(pin "J20"
		)
		(pin "K21"
		)
		(pin "K22"
		)
		(pin "L19"
		)
		(pin "L20"
		)
		(pin "M21"
		)
		(pin "M22"
		)
		(pin "N19"
		)
		(pin "N20"
		)
		(pin "P21"
		)
		(pin "P22"
		)
		(pin "R19"
		)
		(pin "R20"
		)
		(pin "T21"
		)
		(pin "T22"
		)
		(pin "A1"
		)
		(pin "A14"
		)
		(pin "A19"
		)
		(pin "A22"
		)
		(pin "A4"
		)
		(pin "A9"
		)
		(pin "AA14"
		)
		(pin "AA19"
		)
		(pin "AA4"
		)
		(pin "AA9"
		)
		(pin "AB1"
		)
		(pin "AB11"
		)
		(pin "AB16"
		)
		(pin "AB22"
		)
		(pin "AB6"
		)
		(pin "B11"
		)
		(pin "B16"
		)
		(pin "B6"
		)
		(pin "C13"
		)
		(pin "C18"
		)
		(pin "C21"
		)
		(pin "C3"
		)
		(pin "C8"
		)
		(pin "D10"
		)
		(pin "D15"
		)
		(pin "D5"
		)
		(pin "E12"
		)
		(pin "E17"
		)
		(pin "E2"
		)
		(pin "E20"
		)
		(pin "E21"
		)
		(pin "E22"
		)
		(pin "E7"
		)
		(pin "F14"
		)
		(pin "F18"
		)
		(pin "F19"
		)
		(pin "F20"
		)
		(pin "F4"
		)
		(pin "F9"
		)
		(pin "G1"
		)
		(pin "G11"
		)
		(pin "G16"
		)
		(pin "G18"
		)
		(pin "G21"
		)
		(pin "G22"
		)
		(pin "G6"
		)
		(pin "H14"
		)
		(pin "H16"
		)
		(pin "H18"
		)
		(pin "H19"
		)
		(pin "H20"
		)
		(pin "H3"
		)
		(pin "H8"
		)
		(pin "J10"
		)
		(pin "J11"
		)
		(pin "J12"
		)
		(pin "J13"
		)
		(pin "J14"
		)
		(pin "J15"
		)
		(pin "J16"
		)
		(pin "J17"
		)
		(pin "J18"
		)
		(pin "J21"
		)
		(pin "J22"
		)
		(pin "J5"
		)
		(pin "J8"
		)
		(pin "J9"
		)
		(pin "K10"
		)
		(pin "K11"
		)
		(pin "K12"
		)
		(pin "K13"
		)
		(pin "K14"
		)
		(pin "K15"
		)
		(pin "K16"
		)
		(pin "K17"
		)
		(pin "K18"
		)
		(pin "K19"
		)
		(pin "K2"
		)
		(pin "K20"
		)
		(pin "K8"
		)
		(pin "K9"
		)
		(pin "L10"
		)
		(pin "L11"
		)
		(pin "L12"
		)
		(pin "L13"
		)
		(pin "L14"
		)
		(pin "L15"
		)
		(pin "L16"
		)
		(pin "L17"
		)
		(pin "L18"
		)
		(pin "L21"
		)
		(pin "L22"
		)
		(pin "L4"
		)
		(pin "L9"
		)
		(pin "M1"
		)
		(pin "M10"
		)
		(pin "M11"
		)
		(pin "M12"
		)
		(pin "M13"
		)
		(pin "M14"
		)
		(pin "M15"
		)
		(pin "M16"
		)
		(pin "M17"
		)
		(pin "M18"
		)
		(pin "M19"
		)
		(pin "M20"
		)
		(pin "M6"
		)
		(pin "M8"
		)
		(pin "M9"
		)
		(pin "N10"
		)
		(pin "N11"
		)
		(pin "N12"
		)
		(pin "N13"
		)
		(pin "N14"
		)
		(pin "N15"
		)
		(pin "N16"
		)
		(pin "N17"
		)
		(pin "N18"
		)
		(pin "N21"
		)
		(pin "N22"
		)
		(pin "N3"
		)
		(pin "N9"
		)
		(pin "P10"
		)
		(pin "P11"
		)
		(pin "P12"
		)
		(pin "P13"
		)
		(pin "P14"
		)
		(pin "P15"
		)
		(pin "P16"
		)
		(pin "P17"
		)
		(pin "P18"
		)
		(pin "P19"
		)
		(pin "P20"
		)
		(pin "P5"
		)
		(pin "P9"
		)
		(pin "R13"
		)
		(pin "R17"
		)
		(pin "R18"
		)
		(pin "R2"
		)
		(pin "R21"
		)
		(pin "R22"
		)
		(pin "R7"
		)
		(pin "R9"
		)
		(pin "T14"
		)
		(pin "T18"
		)
		(pin "T19"
		)
		(pin "T20"
		)
		(pin "T4"
		)
		(pin "T9"
		)
		(pin "U1"
		)
		(pin "U11"
		)
		(pin "U16"
		)
		(pin "U20"
		)
		(pin "U21"
		)
		(pin "U22"
		)
		(pin "U6"
		)
		(pin "V13"
		)
		(pin "V18"
		)
		(pin "V3"
		)
		(pin "V8"
		)
		(pin "W10"
		)
		(pin "W15"
		)
		(pin "W20"
		)
		(pin "W5"
		)
		(pin "Y12"
		)
		(pin "Y17"
		)
		(pin "Y2"
		)
		(pin "Y22"
		)
		(pin "Y7"
		)
		(instances
			(project "polarfire-som"
				(path ""
					(reference "U1")
					(unit 9)
				)
			)
		)
	)
	(symbol
		(lib_id "antmicroCapacitors0402:C_100n_0402")
		(at 24.13 222.25 90)
		(unit 1)
		(exclude_from_sim no)
		(in_bom yes)
		(on_board yes)
		(dnp no)
		(fields_autoplaced yes)
		(property "Reference" "C7"
			(at 26.67 218.4336 90)
			(effects
				(font
					(size 1.27 1.27)
					(thickness 0.15)
				)
				(justify right)
			)
		)
		(property "Value" "C_100n_0402"
			(at 34.29 201.93 0)
			(effects
				(font
					(size 1.27 1.27)
					(thickness 0.15)
				)
				(justify left bottom)
				(hide yes)
			)
		)
		(property "Footprint" "antmicro-footprints:C_0402_1005Metric"
			(at 36.83 201.93 0)
			(effects
				(font
					(size 1.27 1.27)
					(thickness 0.15)
				)
				(justify left bottom)
				(hide yes)
			)
		)
		(property "Datasheet" "https://www.murata.com/products/productdetail?partno=GRM155R61H104KE14%23"
			(at 39.37 201.93 0)
			(effects
				(font
					(size 1.27 1.27)
					(thickness 0.15)
				)
				(justify left bottom)
				(hide yes)
			)
		)
		(property "Description" "SMD Multilayer Ceramic Capacitor, 0.1 µF, 50 V, 0402 [1005 Metric], ± 10%, X5R, GRM Series"
			(at 24.13 222.25 0)
			(effects
				(font
					(size 1.27 1.27)
				)
				(hide yes)
			)
		)
		(property "MPN" "GRM155R61H104KE14D"
			(at 41.91 201.93 0)
			(effects
				(font
					(size 1.27 1.27)
					(thickness 0.15)
				)
				(justify left bottom)
				(hide yes)
			)
		)
		(property "Manufacturer" "Murata"
			(at 44.45 201.93 0)
			(effects
				(font
					(size 1.27 1.27)
					(thickness 0.15)
				)
				(justify left bottom)
				(hide yes)
			)
		)
		(property "License" "Apache-2.0"
			(at 46.99 201.93 0)
			(effects
				(font
					(size 1.27 1.27)
					(thickness 0.15)
				)
				(justify left bottom)
				(hide yes)
			)
		)
		(property "Author" "Antmicro"
			(at 49.53 201.93 0)
			(effects
				(font
					(size 1.27 1.27)
					(thickness 0.15)
				)
				(justify left bottom)
				(hide yes)
			)
		)
		(property "Val" "100n"
			(at 26.67 220.9736 90)
			(effects
				(font
					(size 1.27 1.27)
					(thickness 0.15)
				)
				(justify right)
			)
		)
		(property "Voltage" "50V"
			(at 52.07 201.93 0)
			(effects
				(font
					(size 1.27 1.27)
				)
				(justify left bottom)
				(hide yes)
			)
		)
		(property "Dielectric" "X5R"
			(at 54.61 201.93 0)
			(effects
				(font
					(size 1.27 1.27)
				)
				(justify left bottom)
				(hide yes)
			)
		)
		(property "Public" ""
			(at 57.15 201.93 0)
			(effects
				(font
					(size 1.27 1.27)
				)
				(justify left bottom)
				(hide yes)
			)
		)
		(pin "1"
		)
		(pin "2"
		)
		(instances
			(project "polarfire-som"
				(path ""
					(reference "C7")
					(unit 1)
				)
			)
		)
	)
	(symbol
		(lib_id "antmicroCapacitors0402:C_10u_0402")
		(at 55.88 246.38 90)
		(unit 1)
		(exclude_from_sim no)
		(in_bom yes)
		(on_board yes)
		(dnp no)
		(fields_autoplaced yes)
		(property "Reference" "C20"
			(at 59.055 242.5635 90)
			(effects
				(font
					(size 1.27 1.27)
					(thickness 0.15)
				)
				(justify right)
			)
		)
		(property "Value" "C_10u_0402"
			(at 66.04 226.06 0)
			(effects
				(font
					(size 1.27 1.27)
					(thickness 0.15)
				)
				(justify left bottom)
				(hide yes)
			)
		)
		(property "Footprint" "antmicro-footprints:C_0402_1005Metric"
			(at 68.58 226.06 0)
			(effects
				(font
					(size 1.27 1.27)
					(thickness 0.15)
				)
				(justify left bottom)
				(hide yes)
			)
		)
		(property "Datasheet" "https://www.yageo.com/en/Chart/Download/pdf/CC0402MRX5R5BB106"
			(at 71.12 226.06 0)
			(effects
				(font
					(size 1.27 1.27)
					(thickness 0.15)
				)
				(justify left bottom)
				(hide yes)
			)
		)
		(property "Description" "SMD Multilayer Ceramic Capacitor, 10 µF, 6.3 V, 0402 [1005 Metric], ± 20%, X5R, CC Series"
			(at 55.88 246.38 0)
			(effects
				(font
					(size 1.27 1.27)
				)
				(hide yes)
			)
		)
		(property "MPN" "CC0402MRX5R5BB106"
			(at 73.66 226.06 0)
			(effects
				(font
					(size 1.27 1.27)
					(thickness 0.15)
				)
				(justify left bottom)
				(hide yes)
			)
		)
		(property "Manufacturer" "YAGEO"
			(at 76.2 226.06 0)
			(effects
				(font
					(size 1.27 1.27)
					(thickness 0.15)
				)
				(justify left bottom)
				(hide yes)
			)
		)
		(property "License" "Apache-2.0"
			(at 78.74 226.06 0)
			(effects
				(font
					(size 1.27 1.27)
					(thickness 0.15)
				)
				(justify left bottom)
				(hide yes)
			)
		)
		(property "Author" "Antmicro"
			(at 81.28 226.06 0)
			(effects
				(font
					(size 1.27 1.27)
					(thickness 0.15)
				)
				(justify left bottom)
				(hide yes)
			)
		)
		(property "Val" "10u"
			(at 59.055 245.1035 90)
			(effects
				(font
					(size 1.27 1.27)
					(thickness 0.15)
				)
				(justify right)
			)
		)
		(property "Voltage" ""
			(at 83.82 226.06 0)
			(effects
				(font
					(size 1.27 1.27)
				)
				(justify left bottom)
				(hide yes)
			)
		)
		(property "Dielectric" ""
			(at 86.36 226.06 0)
			(effects
				(font
					(size 1.27 1.27)
				)
				(justify left bottom)
				(hide yes)
			)
		)
		(property "Public" ""
			(at 88.9 226.06 0)
			(effects
				(font
					(size 1.27 1.27)
				)
				(justify left bottom)
				(hide yes)
			)
		)
		(pin "1"
		)
		(pin "2"
		)
		(instances
			(project "polarfire-som"
				(path ""
					(reference "C20")
					(unit 1)
				)
			)
		)
	)
	(symbol
		(lib_id "antmicroCapacitors0402:C_10u_0402")
		(at 149.86 195.58 90)
		(unit 1)
		(exclude_from_sim no)
		(in_bom yes)
		(on_board yes)
		(dnp no)
		(fields_autoplaced yes)
		(property "Reference" "C49"
			(at 153.035 191.7635 90)
			(effects
				(font
					(size 1.27 1.27)
					(thickness 0.15)
				)
				(justify right)
			)
		)
		(property "Value" "C_10u_0402"
			(at 160.02 175.26 0)
			(effects
				(font
					(size 1.27 1.27)
					(thickness 0.15)
				)
				(justify left bottom)
				(hide yes)
			)
		)
		(property "Footprint" "antmicro-footprints:C_0402_1005Metric"
			(at 162.56 175.26 0)
			(effects
				(font
					(size 1.27 1.27)
					(thickness 0.15)
				)
				(justify left bottom)
				(hide yes)
			)
		)
		(property "Datasheet" "https://www.yageo.com/en/Chart/Download/pdf/CC0402MRX5R5BB106"
			(at 165.1 175.26 0)
			(effects
				(font
					(size 1.27 1.27)
					(thickness 0.15)
				)
				(justify left bottom)
				(hide yes)
			)
		)
		(property "Description" "SMD Multilayer Ceramic Capacitor, 10 µF, 6.3 V, 0402 [1005 Metric], ± 20%, X5R, CC Series"
			(at 149.86 195.58 0)
			(effects
				(font
					(size 1.27 1.27)
				)
				(hide yes)
			)
		)
		(property "MPN" "CC0402MRX5R5BB106"
			(at 167.64 175.26 0)
			(effects
				(font
					(size 1.27 1.27)
					(thickness 0.15)
				)
				(justify left bottom)
				(hide yes)
			)
		)
		(property "Manufacturer" "YAGEO"
			(at 170.18 175.26 0)
			(effects
				(font
					(size 1.27 1.27)
					(thickness 0.15)
				)
				(justify left bottom)
				(hide yes)
			)
		)
		(property "License" "Apache-2.0"
			(at 172.72 175.26 0)
			(effects
				(font
					(size 1.27 1.27)
					(thickness 0.15)
				)
				(justify left bottom)
				(hide yes)
			)
		)
		(property "Author" "Antmicro"
			(at 175.26 175.26 0)
			(effects
				(font
					(size 1.27 1.27)
					(thickness 0.15)
				)
				(justify left bottom)
				(hide yes)
			)
		)
		(property "Val" "10u"
			(at 153.035 194.3035 90)
			(effects
				(font
					(size 1.27 1.27)
					(thickness 0.15)
				)
				(justify right)
			)
		)
		(property "Voltage" ""
			(at 177.8 175.26 0)
			(effects
				(font
					(size 1.27 1.27)
				)
				(justify left bottom)
				(hide yes)
			)
		)
		(property "Dielectric" ""
			(at 180.34 175.26 0)
			(effects
				(font
					(size 1.27 1.27)
				)
				(justify left bottom)
				(hide yes)
			)
		)
		(property "Public" ""
			(at 182.88 175.26 0)
			(effects
				(font
					(size 1.27 1.27)
				)
				(justify left bottom)
				(hide yes)
			)
		)
		(pin "1"
		)
		(pin "2"
		)
		(instances
			(project "polarfire-som"
				(path ""
					(reference "C49")
					(unit 1)
				)
			)
		)
	)
	(symbol
		(lib_id "antmicroCapacitors0402:C_100n_0402")
		(at 99.06 246.38 90)
		(unit 1)
		(exclude_from_sim no)
		(in_bom yes)
		(on_board yes)
		(dnp no)
		(fields_autoplaced yes)
		(property "Reference" "C35"
			(at 101.6 242.5636 90)
			(effects
				(font
					(size 1.27 1.27)
					(thickness 0.15)
				)
				(justify right)
			)
		)
		(property "Value" "C_100n_0402"
			(at 109.22 226.06 0)
			(effects
				(font
					(size 1.27 1.27)
					(thickness 0.15)
				)
				(justify left bottom)
				(hide yes)
			)
		)
		(property "Footprint" "antmicro-footprints:C_0402_1005Metric"
			(at 111.76 226.06 0)
			(effects
				(font
					(size 1.27 1.27)
					(thickness 0.15)
				)
				(justify left bottom)
				(hide yes)
			)
		)
		(property "Datasheet" "https://www.murata.com/products/productdetail?partno=GRM155R61H104KE14%23"
			(at 114.3 226.06 0)
			(effects
				(font
					(size 1.27 1.27)
					(thickness 0.15)
				)
				(justify left bottom)
				(hide yes)
			)
		)
		(property "Description" "SMD Multilayer Ceramic Capacitor, 0.1 µF, 50 V, 0402 [1005 Metric], ± 10%, X5R, GRM Series"
			(at 99.06 246.38 0)
			(effects
				(font
					(size 1.27 1.27)
				)
				(hide yes)
			)
		)
		(property "MPN" "GRM155R61H104KE14D"
			(at 116.84 226.06 0)
			(effects
				(font
					(size 1.27 1.27)
					(thickness 0.15)
				)
				(justify left bottom)
				(hide yes)
			)
		)
		(property "Manufacturer" "Murata"
			(at 119.38 226.06 0)
			(effects
				(font
					(size 1.27 1.27)
					(thickness 0.15)
				)
				(justify left bottom)
				(hide yes)
			)
		)
		(property "License" "Apache-2.0"
			(at 121.92 226.06 0)
			(effects
				(font
					(size 1.27 1.27)
					(thickness 0.15)
				)
				(justify left bottom)
				(hide yes)
			)
		)
		(property "Author" "Antmicro"
			(at 124.46 226.06 0)
			(effects
				(font
					(size 1.27 1.27)
					(thickness 0.15)
				)
				(justify left bottom)
				(hide yes)
			)
		)
		(property "Val" "100n"
			(at 101.6 245.1036 90)
			(effects
				(font
					(size 1.27 1.27)
					(thickness 0.15)
				)
				(justify right)
			)
		)
		(property "Voltage" "50V"
			(at 127 226.06 0)
			(effects
				(font
					(size 1.27 1.27)
				)
				(justify left bottom)
				(hide yes)
			)
		)
		(property "Dielectric" "X5R"
			(at 129.54 226.06 0)
			(effects
				(font
					(size 1.27 1.27)
				)
				(justify left bottom)
				(hide yes)
			)
		)
		(property "Public" ""
			(at 132.08 226.06 0)
			(effects
				(font
					(size 1.27 1.27)
				)
				(justify left bottom)
				(hide yes)
			)
		)
		(pin "1"
		)
		(pin "2"
		)
		(instances
			(project "polarfire-som"
				(path ""
					(reference "C35")
					(unit 1)
				)
			)
		)
	)
	(symbol
		(lib_id "antmicropower:VDDAUX")
		(at 168.91 85.09 0)
		(unit 1)
		(exclude_from_sim no)
		(in_bom yes)
		(on_board yes)
		(dnp no)
		(property "Reference" "#PWR0330"
			(at 168.91 88.9 0)
			(effects
				(font
					(size 1.27 1.27)
				)
				(hide yes)
			)
		)
		(property "Value" "VDDAUX"
			(at 168.91 81.28 0)
			(effects
				(font
					(size 1.27 1.27)
				)
			)
		)
		(property "Footprint" ""
			(at 168.91 85.09 0)
			(effects
				(font
					(size 1.27 1.27)
				)
				(hide yes)
			)
		)
		(property "Datasheet" ""
			(at 168.91 85.09 0)
			(effects
				(font
					(size 1.27 1.27)
				)
				(hide yes)
			)
		)
		(property "Description" ""
			(at 168.91 85.09 0)
			(effects
				(font
					(size 1.27 1.27)
				)
				(hide yes)
			)
		)
		(pin "1"
		)
		(instances
			(project "polarfire-som"
				(path ""
					(reference "#PWR0330")
					(unit 1)
				)
			)
		)
	)
	(symbol
		(lib_id "antmicroCapacitors0402:C_100n_0402")
		(at 172.72 222.25 90)
		(unit 1)
		(exclude_from_sim no)
		(in_bom yes)
		(on_board yes)
		(dnp no)
		(fields_autoplaced yes)
		(property "Reference" "C61"
			(at 175.26 218.4336 90)
			(effects
				(font
					(size 1.27 1.27)
					(thickness 0.15)
				)
				(justify right)
			)
		)
		(property "Value" "C_100n_0402"
			(at 182.88 201.93 0)
			(effects
				(font
					(size 1.27 1.27)
					(thickness 0.15)
				)
				(justify left bottom)
				(hide yes)
			)
		)
		(property "Footprint" "antmicro-footprints:C_0402_1005Metric"
			(at 185.42 201.93 0)
			(effects
				(font
					(size 1.27 1.27)
					(thickness 0.15)
				)
				(justify left bottom)
				(hide yes)
			)
		)
		(property "Datasheet" "https://www.murata.com/products/productdetail?partno=GRM155R61H104KE14%23"
			(at 187.96 201.93 0)
			(effects
				(font
					(size 1.27 1.27)
					(thickness 0.15)
				)
				(justify left bottom)
				(hide yes)
			)
		)
		(property "Description" "SMD Multilayer Ceramic Capacitor, 0.1 µF, 50 V, 0402 [1005 Metric], ± 10%, X5R, GRM Series"
			(at 172.72 222.25 0)
			(effects
				(font
					(size 1.27 1.27)
				)
				(hide yes)
			)
		)
		(property "MPN" "GRM155R61H104KE14D"
			(at 190.5 201.93 0)
			(effects
				(font
					(size 1.27 1.27)
					(thickness 0.15)
				)
				(justify left bottom)
				(hide yes)
			)
		)
		(property "Manufacturer" "Murata"
			(at 193.04 201.93 0)
			(effects
				(font
					(size 1.27 1.27)
					(thickness 0.15)
				)
				(justify left bottom)
				(hide yes)
			)
		)
		(property "License" "Apache-2.0"
			(at 195.58 201.93 0)
			(effects
				(font
					(size 1.27 1.27)
					(thickness 0.15)
				)
				(justify left bottom)
				(hide yes)
			)
		)
		(property "Author" "Antmicro"
			(at 198.12 201.93 0)
			(effects
				(font
					(size 1.27 1.27)
					(thickness 0.15)
				)
				(justify left bottom)
				(hide yes)
			)
		)
		(property "Val" "100n"
			(at 175.26 220.9736 90)
			(effects
				(font
					(size 1.27 1.27)
					(thickness 0.15)
				)
				(justify right)
			)
		)
		(property "Voltage" "50V"
			(at 200.66 201.93 0)
			(effects
				(font
					(size 1.27 1.27)
				)
				(justify left bottom)
				(hide yes)
			)
		)
		(property "Dielectric" "X5R"
			(at 203.2 201.93 0)
			(effects
				(font
					(size 1.27 1.27)
				)
				(justify left bottom)
				(hide yes)
			)
		)
		(property "Public" ""
			(at 205.74 201.93 0)
			(effects
				(font
					(size 1.27 1.27)
				)
				(justify left bottom)
				(hide yes)
			)
		)
		(pin "1"
		)
		(pin "2"
		)
		(instances
			(project "polarfire-som"
				(path ""
					(reference "C61")
					(unit 1)
				)
			)
		)
	)
	(symbol
		(lib_id "antmicroCapacitors0402:C_4n7_0402")
		(at 162.56 222.25 90)
		(unit 1)
		(exclude_from_sim no)
		(in_bom yes)
		(on_board yes)
		(dnp no)
		(fields_autoplaced yes)
		(property "Reference" "C56"
			(at 165.1 218.4336 90)
			(effects
				(font
					(size 1.27 1.27)
					(thickness 0.15)
				)
				(justify right)
			)
		)
		(property "Value" "C_4n7_0402"
			(at 172.72 201.93 0)
			(effects
				(font
					(size 1.27 1.27)
					(thickness 0.15)
				)
				(justify left bottom)
				(hide yes)
			)
		)
		(property "Footprint" "antmicro-footprints:C_0402_1005Metric"
			(at 175.26 201.93 0)
			(effects
				(font
					(size 1.27 1.27)
					(thickness 0.15)
				)
				(justify left bottom)
				(hide yes)
			)
		)
		(property "Datasheet" "https://product.tdk.com/en/search/capacitor/ceramic/mlcc/info?part_no=CGA2B3X7S2A472K050BB"
			(at 177.8 201.93 0)
			(effects
				(font
					(size 1.27 1.27)
					(thickness 0.15)
				)
				(justify left bottom)
				(hide yes)
			)
		)
		(property "Description" "SMD Multilayer Ceramic Capacitor, 4700 pF, 100 V, 0402 [1005 Metric], ± 10%, X7S, CGA"
			(at 162.56 222.25 0)
			(effects
				(font
					(size 1.27 1.27)
				)
				(hide yes)
			)
		)
		(property "MPN" "CGA2B3X7S2A472K050BB"
			(at 180.34 201.93 0)
			(effects
				(font
					(size 1.27 1.27)
					(thickness 0.15)
				)
				(justify left bottom)
				(hide yes)
			)
		)
		(property "Manufacturer" "TDK"
			(at 182.88 201.93 0)
			(effects
				(font
					(size 1.27 1.27)
					(thickness 0.15)
				)
				(justify left bottom)
				(hide yes)
			)
		)
		(property "License" "Apache-2.0"
			(at 185.42 201.93 0)
			(effects
				(font
					(size 1.27 1.27)
					(thickness 0.15)
				)
				(justify left bottom)
				(hide yes)
			)
		)
		(property "Author" "Antmicro"
			(at 187.96 201.93 0)
			(effects
				(font
					(size 1.27 1.27)
					(thickness 0.15)
				)
				(justify left bottom)
				(hide yes)
			)
		)
		(property "Val" "4n7"
			(at 165.1 220.9736 90)
			(effects
				(font
					(size 1.27 1.27)
					(thickness 0.15)
				)
				(justify right)
			)
		)
		(property "Voltage" "25V"
			(at 190.5 201.93 0)
			(effects
				(font
					(size 1.27 1.27)
				)
				(justify left bottom)
				(hide yes)
			)
		)
		(property "Dielectric" "X7R"
			(at 193.04 201.93 0)
			(effects
				(font
					(size 1.27 1.27)
				)
				(justify left bottom)
				(hide yes)
			)
		)
		(property "Public" ""
			(at 195.58 201.93 0)
			(effects
				(font
					(size 1.27 1.27)
				)
				(justify left bottom)
				(hide yes)
			)
		)
		(pin "1"
		)
		(pin "2"
		)
		(instances
			(project "polarfire-som"
				(path ""
					(reference "C56")
					(unit 1)
				)
			)
		)
	)
	(symbol
		(lib_id "antmicropower:+1V05")
		(at 78.74 238.76 0)
		(unit 1)
		(exclude_from_sim no)
		(in_bom yes)
		(on_board yes)
		(dnp no)
		(property "Reference" "#PWR019"
			(at 78.74 242.57 0)
			(effects
				(font
					(size 1.27 1.27)
				)
				(hide yes)
			)
		)
		(property "Value" "+1V05"
			(at 78.74 234.95 0)
			(effects
				(font
					(size 1.27 1.27)
				)
			)
		)
		(property "Footprint" ""
			(at 78.74 238.76 0)
			(effects
				(font
					(size 1.27 1.27)
				)
				(hide yes)
			)
		)
		(property "Datasheet" ""
			(at 78.74 238.76 0)
			(effects
				(font
					(size 1.27 1.27)
				)
				(hide yes)
			)
		)
		(property "Description" ""
			(at 78.74 238.76 0)
			(effects
				(font
					(size 1.27 1.27)
				)
				(hide yes)
			)
		)
		(pin "1"
		)
		(instances
			(project "polarfire-som"
				(path ""
					(reference "#PWR019")
					(unit 1)
				)
			)
		)
	)
	(symbol
		(lib_id "antmicropower:GND")
		(at 71.12 223.52 0)
		(unit 1)
		(exclude_from_sim no)
		(in_bom yes)
		(on_board yes)
		(dnp no)
		(property "Reference" "#PWR018"
			(at 80.01 226.06 0)
			(effects
				(font
					(size 1.27 1.27)
					(thickness 0.15)
				)
				(justify left bottom)
				(hide yes)
			)
		)
		(property "Value" "GND"
			(at 71.12 227.33 0)
			(effects
				(font
					(size 1.27 1.27)
					(thickness 0.15)
				)
			)
		)
		(property "Footprint" ""
			(at 80.01 231.14 0)
			(effects
				(font
					(size 1.27 1.27)
					(thickness 0.15)
				)
				(justify left bottom)
				(hide yes)
			)
		)
		(property "Datasheet" ""
			(at 80.01 236.22 0)
			(effects
				(font
					(size 1.27 1.27)
					(thickness 0.15)
				)
				(justify left bottom)
				(hide yes)
			)
		)
		(property "Description" ""
			(at 71.12 223.52 0)
			(effects
				(font
					(size 1.27 1.27)
				)
				(hide yes)
			)
		)
		(property "Author" "Antmicro"
			(at 80.01 231.14 0)
			(effects
				(font
					(size 1.27 1.27)
					(thickness 0.15)
				)
				(justify left bottom)
				(hide yes)
			)
		)
		(property "License" "Apache-2.0"
			(at 80.01 233.68 0)
			(effects
				(font
					(size 1.27 1.27)
					(thickness 0.15)
				)
				(justify left bottom)
				(hide yes)
			)
		)
		(pin "1"
		)
		(instances
			(project "polarfire-som"
				(path ""
					(reference "#PWR018")
					(unit 1)
				)
			)
		)
	)
	(symbol
		(lib_id "antmicropower:+2V5")
		(at 229.87 95.25 270)
		(unit 1)
		(exclude_from_sim no)
		(in_bom yes)
		(on_board yes)
		(dnp no)
		(property "Reference" "#PWR043"
			(at 226.06 95.25 0)
			(effects
				(font
					(size 1.27 1.27)
				)
				(hide yes)
			)
		)
		(property "Value" "+2V5"
			(at 234.95 95.25 90)
			(effects
				(font
					(size 1.27 1.27)
				)
			)
		)
		(property "Footprint" ""
			(at 229.87 95.25 0)
			(effects
				(font
					(size 1.27 1.27)
				)
				(hide yes)
			)
		)
		(property "Datasheet" ""
			(at 229.87 95.25 0)
			(effects
				(font
					(size 1.27 1.27)
				)
				(hide yes)
			)
		)
		(property "Description" ""
			(at 229.87 95.25 0)
			(effects
				(font
					(size 1.27 1.27)
				)
				(hide yes)
			)
		)
		(pin "1"
		)
		(instances
			(project "polarfire-som"
				(path ""
					(reference "#PWR043")
					(unit 1)
				)
			)
		)
	)
	(symbol
		(lib_id "antmicroCapacitors0402:C_100n_0402")
		(at 20.32 246.38 90)
		(unit 1)
		(exclude_from_sim no)
		(in_bom yes)
		(on_board yes)
		(dnp no)
		(fields_autoplaced yes)
		(property "Reference" "C8"
			(at 22.86 242.5636 90)
			(effects
				(font
					(size 1.27 1.27)
					(thickness 0.15)
				)
				(justify right)
			)
		)
		(property "Value" "C_100n_0402"
			(at 30.48 226.06 0)
			(effects
				(font
					(size 1.27 1.27)
					(thickness 0.15)
				)
				(justify left bottom)
				(hide yes)
			)
		)
		(property "Footprint" "antmicro-footprints:C_0402_1005Metric"
			(at 33.02 226.06 0)
			(effects
				(font
					(size 1.27 1.27)
					(thickness 0.15)
				)
				(justify left bottom)
				(hide yes)
			)
		)
		(property "Datasheet" "https://www.murata.com/products/productdetail?partno=GRM155R61H104KE14%23"
			(at 35.56 226.06 0)
			(effects
				(font
					(size 1.27 1.27)
					(thickness 0.15)
				)
				(justify left bottom)
				(hide yes)
			)
		)
		(property "Description" "SMD Multilayer Ceramic Capacitor, 0.1 µF, 50 V, 0402 [1005 Metric], ± 10%, X5R, GRM Series"
			(at 20.32 246.38 0)
			(effects
				(font
					(size 1.27 1.27)
				)
				(hide yes)
			)
		)
		(property "MPN" "GRM155R61H104KE14D"
			(at 38.1 226.06 0)
			(effects
				(font
					(size 1.27 1.27)
					(thickness 0.15)
				)
				(justify left bottom)
				(hide yes)
			)
		)
		(property "Manufacturer" "Murata"
			(at 40.64 226.06 0)
			(effects
				(font
					(size 1.27 1.27)
					(thickness 0.15)
				)
				(justify left bottom)
				(hide yes)
			)
		)
		(property "License" "Apache-2.0"
			(at 43.18 226.06 0)
			(effects
				(font
					(size 1.27 1.27)
					(thickness 0.15)
				)
				(justify left bottom)
				(hide yes)
			)
		)
		(property "Author" "Antmicro"
			(at 45.72 226.06 0)
			(effects
				(font
					(size 1.27 1.27)
					(thickness 0.15)
				)
				(justify left bottom)
				(hide yes)
			)
		)
		(property "Val" "100n"
			(at 22.86 245.1036 90)
			(effects
				(font
					(size 1.27 1.27)
					(thickness 0.15)
				)
				(justify right)
			)
		)
		(property "Voltage" "50V"
			(at 48.26 226.06 0)
			(effects
				(font
					(size 1.27 1.27)
				)
				(justify left bottom)
				(hide yes)
			)
		)
		(property "Dielectric" "X5R"
			(at 50.8 226.06 0)
			(effects
				(font
					(size 1.27 1.27)
				)
				(justify left bottom)
				(hide yes)
			)
		)
		(property "Public" ""
			(at 53.34 226.06 0)
			(effects
				(font
					(size 1.27 1.27)
				)
				(justify left bottom)
				(hide yes)
			)
		)
		(pin "1"
		)
		(pin "2"
		)
		(instances
			(project "polarfire-som"
				(path ""
					(reference "C8")
					(unit 1)
				)
			)
		)
	)
	(symbol
		(lib_id "antmicroCapacitors0402:C_4n7_0402")
		(at 88.9 246.38 90)
		(unit 1)
		(exclude_from_sim no)
		(in_bom yes)
		(on_board yes)
		(dnp no)
		(fields_autoplaced yes)
		(property "Reference" "C24"
			(at 91.44 242.5636 90)
			(effects
				(font
					(size 1.27 1.27)
					(thickness 0.15)
				)
				(justify right)
			)
		)
		(property "Value" "C_4n7_0402"
			(at 99.06 226.06 0)
			(effects
				(font
					(size 1.27 1.27)
					(thickness 0.15)
				)
				(justify left bottom)
				(hide yes)
			)
		)
		(property "Footprint" "antmicro-footprints:C_0402_1005Metric"
			(at 101.6 226.06 0)
			(effects
				(font
					(size 1.27 1.27)
					(thickness 0.15)
				)
				(justify left bottom)
				(hide yes)
			)
		)
		(property "Datasheet" "https://product.tdk.com/en/search/capacitor/ceramic/mlcc/info?part_no=CGA2B3X7S2A472K050BB"
			(at 104.14 226.06 0)
			(effects
				(font
					(size 1.27 1.27)
					(thickness 0.15)
				)
				(justify left bottom)
				(hide yes)
			)
		)
		(property "Description" "SMD Multilayer Ceramic Capacitor, 4700 pF, 100 V, 0402 [1005 Metric], ± 10%, X7S, CGA"
			(at 88.9 246.38 0)
			(effects
				(font
					(size 1.27 1.27)
				)
				(hide yes)
			)
		)
		(property "MPN" "CGA2B3X7S2A472K050BB"
			(at 106.68 226.06 0)
			(effects
				(font
					(size 1.27 1.27)
					(thickness 0.15)
				)
				(justify left bottom)
				(hide yes)
			)
		)
		(property "Manufacturer" "TDK"
			(at 109.22 226.06 0)
			(effects
				(font
					(size 1.27 1.27)
					(thickness 0.15)
				)
				(justify left bottom)
				(hide yes)
			)
		)
		(property "License" "Apache-2.0"
			(at 111.76 226.06 0)
			(effects
				(font
					(size 1.27 1.27)
					(thickness 0.15)
				)
				(justify left bottom)
				(hide yes)
			)
		)
		(property "Author" "Antmicro"
			(at 114.3 226.06 0)
			(effects
				(font
					(size 1.27 1.27)
					(thickness 0.15)
				)
				(justify left bottom)
				(hide yes)
			)
		)
		(property "Val" "4n7"
			(at 91.44 245.1036 90)
			(effects
				(font
					(size 1.27 1.27)
					(thickness 0.15)
				)
				(justify right)
			)
		)
		(property "Voltage" "25V"
			(at 116.84 226.06 0)
			(effects
				(font
					(size 1.27 1.27)
				)
				(justify left bottom)
				(hide yes)
			)
		)
		(property "Dielectric" "X7R"
			(at 119.38 226.06 0)
			(effects
				(font
					(size 1.27 1.27)
				)
				(justify left bottom)
				(hide yes)
			)
		)
		(property "Public" ""
			(at 121.92 226.06 0)
			(effects
				(font
					(size 1.27 1.27)
				)
				(justify left bottom)
				(hide yes)
			)
		)
		(pin "1"
		)
		(pin "2"
		)
		(instances
			(project "polarfire-som"
				(path ""
					(reference "C24")
					(unit 1)
				)
			)
		)
	)
	(symbol
		(lib_id "antmicropower:+3V3")
		(at 24.13 189.23 0)
		(unit 1)
		(exclude_from_sim no)
		(in_bom yes)
		(on_board yes)
		(dnp no)
		(property "Reference" "#PWR010"
			(at 39.37 189.23 0)
			(effects
				(font
					(size 1.27 1.27)
					(thickness 0.15)
				)
				(justify left bottom)
				(hide yes)
			)
		)
		(property "Value" "+3V3"
			(at 24.13 185.42 0)
			(effects
				(font
					(size 1.27 1.27)
					(thickness 0.15)
				)
			)
		)
		(property "Footprint" ""
			(at 39.37 196.85 0)
			(effects
				(font
					(size 1.27 1.27)
					(thickness 0.15)
				)
				(justify left bottom)
				(hide yes)
			)
		)
		(property "Datasheet" ""
			(at 39.37 199.39 0)
			(effects
				(font
					(size 1.27 1.27)
					(thickness 0.15)
				)
				(justify left bottom)
				(hide yes)
			)
		)
		(property "Description" ""
			(at 24.13 189.23 0)
			(effects
				(font
					(size 1.27 1.27)
				)
				(hide yes)
			)
		)
		(property "Author" "Antmicro"
			(at 39.37 191.77 0)
			(effects
				(font
					(size 1.27 1.27)
					(thickness 0.15)
				)
				(justify left bottom)
				(hide yes)
			)
		)
		(property "License" "Apache-2.0"
			(at 39.37 194.31 0)
			(effects
				(font
					(size 1.27 1.27)
					(thickness 0.15)
				)
				(justify left bottom)
				(hide yes)
			)
		)
		(pin "1"
		)
		(instances
			(project "polarfire-som"
				(path ""
					(reference "#PWR010")
					(unit 1)
				)
			)
		)
	)
	(symbol
		(lib_id "antmicropower:PWR_FLAG")
		(at 176.53 161.29 0)
		(unit 1)
		(exclude_from_sim no)
		(in_bom yes)
		(on_board yes)
		(dnp no)
		(property "Reference" "#FLG08"
			(at 176.53 159.385 0)
			(effects
				(font
					(size 1.27 1.27)
				)
				(hide yes)
			)
		)
		(property "Value" "PWR_FLAG"
			(at 176.53 157.226 0)
			(effects
				(font
					(size 1.27 1.27)
				)
			)
		)
		(property "Footprint" ""
			(at 176.53 161.29 0)
			(effects
				(font
					(size 1.27 1.27)
				)
				(hide yes)
			)
		)
		(property "Datasheet" ""
			(at 176.53 161.29 0)
			(effects
				(font
					(size 1.27 1.27)
				)
				(hide yes)
			)
		)
		(property "Description" ""
			(at 176.53 161.29 0)
			(effects
				(font
					(size 1.27 1.27)
				)
				(hide yes)
			)
		)
		(pin "1"
		)
		(instances
			(project "polarfire-som"
				(path ""
					(reference "#FLG08")
					(unit 1)
				)
			)
		)
	)
	(symbol
		(lib_id "antmicroCapacitors0402:C_100n_0402")
		(at 60.96 195.58 90)
		(unit 1)
		(exclude_from_sim no)
		(in_bom yes)
		(on_board yes)
		(dnp no)
		(fields_autoplaced yes)
		(property "Reference" "C14"
			(at 63.5 191.7636 90)
			(effects
				(font
					(size 1.27 1.27)
					(thickness 0.15)
				)
				(justify right)
			)
		)
		(property "Value" "C_100n_0402"
			(at 71.12 175.26 0)
			(effects
				(font
					(size 1.27 1.27)
					(thickness 0.15)
				)
				(justify left bottom)
				(hide yes)
			)
		)
		(property "Footprint" "antmicro-footprints:C_0402_1005Metric"
			(at 73.66 175.26 0)
			(effects
				(font
					(size 1.27 1.27)
					(thickness 0.15)
				)
				(justify left bottom)
				(hide yes)
			)
		)
		(property "Datasheet" "https://www.murata.com/products/productdetail?partno=GRM155R61H104KE14%23"
			(at 76.2 175.26 0)
			(effects
				(font
					(size 1.27 1.27)
					(thickness 0.15)
				)
				(justify left bottom)
				(hide yes)
			)
		)
		(property "Description" "SMD Multilayer Ceramic Capacitor, 0.1 µF, 50 V, 0402 [1005 Metric], ± 10%, X5R, GRM Series"
			(at 60.96 195.58 0)
			(effects
				(font
					(size 1.27 1.27)
				)
				(hide yes)
			)
		)
		(property "MPN" "GRM155R61H104KE14D"
			(at 78.74 175.26 0)
			(effects
				(font
					(size 1.27 1.27)
					(thickness 0.15)
				)
				(justify left bottom)
				(hide yes)
			)
		)
		(property "Manufacturer" "Murata"
			(at 81.28 175.26 0)
			(effects
				(font
					(size 1.27 1.27)
					(thickness 0.15)
				)
				(justify left bottom)
				(hide yes)
			)
		)
		(property "License" "Apache-2.0"
			(at 83.82 175.26 0)
			(effects
				(font
					(size 1.27 1.27)
					(thickness 0.15)
				)
				(justify left bottom)
				(hide yes)
			)
		)
		(property "Author" "Antmicro"
			(at 86.36 175.26 0)
			(effects
				(font
					(size 1.27 1.27)
					(thickness 0.15)
				)
				(justify left bottom)
				(hide yes)
			)
		)
		(property "Val" "100n"
			(at 63.5 194.3036 90)
			(effects
				(font
					(size 1.27 1.27)
					(thickness 0.15)
				)
				(justify right)
			)
		)
		(property "Voltage" "50V"
			(at 88.9 175.26 0)
			(effects
				(font
					(size 1.27 1.27)
				)
				(justify left bottom)
				(hide yes)
			)
		)
		(property "Dielectric" "X5R"
			(at 91.44 175.26 0)
			(effects
				(font
					(size 1.27 1.27)
				)
				(justify left bottom)
				(hide yes)
			)
		)
		(property "Public" ""
			(at 93.98 175.26 0)
			(effects
				(font
					(size 1.27 1.27)
				)
				(justify left bottom)
				(hide yes)
			)
		)
		(pin "1"
		)
		(pin "2"
		)
		(instances
			(project "polarfire-som"
				(path ""
					(reference "C14")
					(unit 1)
				)
			)
		)
	)
	(symbol
		(lib_id "antmicroCapacitorspol:C_Pol_330u_6.3V_KEMET-T520-B")
		(at 172.72 190.5 270)
		(unit 1)
		(exclude_from_sim no)
		(in_bom yes)
		(on_board yes)
		(dnp no)
		(property "Reference" "C60"
			(at 175.26 191.77 90)
			(effects
				(font
					(size 1.27 1.27)
					(thickness 0.15)
				)
				(justify left)
			)
		)
		(property "Value" "C_Pol_330u_6.3V_KEMET-T520-B"
			(at 170.18 204.47 0)
			(effects
				(font
					(size 1.27 1.27)
					(thickness 0.15)
				)
				(justify left bottom)
				(hide yes)
			)
		)
		(property "Footprint" "antmicro-footprints:C_Pol_EIA-B"
			(at 165.1 204.47 0)
			(effects
				(font
					(size 1.27 1.27)
					(thickness 0.15)
				)
				(justify left bottom)
				(hide yes)
			)
		)
		(property "Datasheet" "https://www.kemet.com/en/us/capacitors/product/T520B337M006ATE040.html"
			(at 162.56 204.47 0)
			(effects
				(font
					(size 1.27 1.27)
					(thickness 0.15)
				)
				(justify left bottom)
				(hide yes)
			)
		)
		(property "Description" "Tantalum Polymer Capacitor, KO-CAP®, 330 µF, ± 20%, 6.3 V, B, 0.04 ohm, 1411 [3528 Metric]"
			(at 172.72 190.5 0)
			(effects
				(font
					(size 1.27 1.27)
				)
				(hide yes)
			)
		)
		(property "Val" "330u"
			(at 175.26 194.31 90)
			(effects
				(font
					(size 1.27 1.27)
					(thickness 0.15)
				)
				(justify left)
				(hide yes)
			)
		)
		(property "MPN" "T520B337M006ATE040"
			(at 160.02 204.47 0)
			(effects
				(font
					(size 1.27 1.27)
					(thickness 0.15)
				)
				(justify left bottom)
				(hide yes)
			)
		)
		(property "Manufacturer" "KEMET"
			(at 157.48 204.47 0)
			(effects
				(font
					(size 1.27 1.27)
					(thickness 0.15)
				)
				(justify left bottom)
				(hide yes)
			)
		)
		(property "License" "Apache-2.0"
			(at 154.94 204.47 0)
			(effects
				(font
					(size 1.27 1.27)
					(thickness 0.15)
				)
				(justify left bottom)
				(hide yes)
			)
		)
		(property "Author" "Antmicro"
			(at 152.4 204.47 0)
			(effects
				(font
					(size 1.27 1.27)
					(thickness 0.15)
				)
				(justify left bottom)
				(hide yes)
			)
		)
		(property "Voltage" "6.3V"
			(at 149.86 204.47 0)
			(effects
				(font
					(size 1.27 1.27)
				)
				(justify left bottom)
				(hide yes)
			)
		)
		(property "Dielectric" "template_dielectric"
			(at 147.32 204.47 0)
			(effects
				(font
					(size 1.27 1.27)
				)
				(justify left bottom)
				(hide yes)
			)
		)
		(property "Capacitance" "330u"
			(at 175.26 194.31 90)
			(effects
				(font
					(size 1.27 1.27)
				)
				(justify left)
			)
		)
		(property "Public" ""
			(at 144.78 204.47 0)
			(effects
				(font
					(size 1.27 1.27)
				)
				(justify left bottom)
				(hide yes)
			)
		)
		(pin "1"
		)
		(pin "2"
		)
		(instances
			(project "polarfire-som"
				(path ""
					(reference "C60")
					(unit 1)
				)
			)
		)
	)
	(symbol
		(lib_id "antmicroCapacitors0603:C_47u_0603")
		(at 71.12 168.91 90)
		(unit 1)
		(exclude_from_sim no)
		(in_bom yes)
		(on_board yes)
		(dnp no)
		(fields_autoplaced yes)
		(property "Reference" "C21"
			(at 73.66 165.0936 90)
			(effects
				(font
					(size 1.27 1.27)
					(thickness 0.15)
				)
				(justify right)
			)
		)
		(property "Value" "C_47u_0603"
			(at 81.28 148.59 0)
			(effects
				(font
					(size 1.27 1.27)
					(thickness 0.15)
				)
				(justify left bottom)
				(hide yes)
			)
		)
		(property "Footprint" "antmicro-footprints:C_0603_1608Metric"
			(at 83.82 148.59 0)
			(effects
				(font
					(size 1.27 1.27)
					(thickness 0.15)
				)
				(justify left bottom)
				(hide yes)
			)
		)
		(property "Datasheet" "https://www.murata.com/products/productdetail?partno=GRM188R60J476ME15%23"
			(at 86.36 148.59 0)
			(effects
				(font
					(size 1.27 1.27)
					(thickness 0.15)
				)
				(justify left bottom)
				(hide yes)
			)
		)
		(property "Description" "SMD Multilayer Ceramic Capacitor, 47 µF, 6.3 V, 0603 [1608 Metric], ± 20%, X5R, GRM Series"
			(at 71.12 168.91 0)
			(effects
				(font
					(size 1.27 1.27)
				)
				(hide yes)
			)
		)
		(property "MPN" "GRM188R60J476ME15D"
			(at 88.9 148.59 0)
			(effects
				(font
					(size 1.27 1.27)
					(thickness 0.15)
				)
				(justify left bottom)
				(hide yes)
			)
		)
		(property "Manufacturer" "Murata"
			(at 91.44 148.59 0)
			(effects
				(font
					(size 1.27 1.27)
					(thickness 0.15)
				)
				(justify left bottom)
				(hide yes)
			)
		)
		(property "License" "Apache-2.0"
			(at 93.98 148.59 0)
			(effects
				(font
					(size 1.27 1.27)
					(thickness 0.15)
				)
				(justify left bottom)
				(hide yes)
			)
		)
		(property "Author" "Antmicro"
			(at 96.52 148.59 0)
			(effects
				(font
					(size 1.27 1.27)
					(thickness 0.15)
				)
				(justify left bottom)
				(hide yes)
			)
		)
		(property "Val" "47u"
			(at 73.66 167.6336 90)
			(effects
				(font
					(size 1.27 1.27)
					(thickness 0.15)
				)
				(justify right)
			)
		)
		(property "Voltage" "50V"
			(at 99.06 148.59 0)
			(effects
				(font
					(size 1.27 1.27)
				)
				(justify left bottom)
				(hide yes)
			)
		)
		(property "Dielectric" "X7R"
			(at 101.6 148.59 0)
			(effects
				(font
					(size 1.27 1.27)
				)
				(justify left bottom)
				(hide yes)
			)
		)
		(property "Capacitance" "47u"
			(at 73.66 167.64 90)
			(effects
				(font
					(size 1.27 1.27)
				)
				(justify right)
				(hide yes)
			)
		)
		(property "Public" ""
			(at 104.14 148.59 0)
			(effects
				(font
					(size 1.27 1.27)
				)
				(justify left bottom)
				(hide yes)
			)
		)
		(pin "1"
		)
		(pin "2"
		)
		(instances
			(project "polarfire-som"
				(path ""
					(reference "C21")
					(unit 1)
				)
			)
		)
	)
	(symbol
		(lib_id "antmicroCapacitors0402:C_100n_0402")
		(at 60.96 220.98 90)
		(unit 1)
		(exclude_from_sim no)
		(in_bom yes)
		(on_board yes)
		(dnp no)
		(fields_autoplaced yes)
		(property "Reference" "C15"
			(at 63.5 217.1636 90)
			(effects
				(font
					(size 1.27 1.27)
					(thickness 0.15)
				)
				(justify right)
			)
		)
		(property "Value" "C_100n_0402"
			(at 71.12 200.66 0)
			(effects
				(font
					(size 1.27 1.27)
					(thickness 0.15)
				)
				(justify left bottom)
				(hide yes)
			)
		)
		(property "Footprint" "antmicro-footprints:C_0402_1005Metric"
			(at 73.66 200.66 0)
			(effects
				(font
					(size 1.27 1.27)
					(thickness 0.15)
				)
				(justify left bottom)
				(hide yes)
			)
		)
		(property "Datasheet" "https://www.murata.com/products/productdetail?partno=GRM155R61H104KE14%23"
			(at 76.2 200.66 0)
			(effects
				(font
					(size 1.27 1.27)
					(thickness 0.15)
				)
				(justify left bottom)
				(hide yes)
			)
		)
		(property "Description" "SMD Multilayer Ceramic Capacitor, 0.1 µF, 50 V, 0402 [1005 Metric], ± 10%, X5R, GRM Series"
			(at 60.96 220.98 0)
			(effects
				(font
					(size 1.27 1.27)
				)
				(hide yes)
			)
		)
		(property "MPN" "GRM155R61H104KE14D"
			(at 78.74 200.66 0)
			(effects
				(font
					(size 1.27 1.27)
					(thickness 0.15)
				)
				(justify left bottom)
				(hide yes)
			)
		)
		(property "Manufacturer" "Murata"
			(at 81.28 200.66 0)
			(effects
				(font
					(size 1.27 1.27)
					(thickness 0.15)
				)
				(justify left bottom)
				(hide yes)
			)
		)
		(property "License" "Apache-2.0"
			(at 83.82 200.66 0)
			(effects
				(font
					(size 1.27 1.27)
					(thickness 0.15)
				)
				(justify left bottom)
				(hide yes)
			)
		)
		(property "Author" "Antmicro"
			(at 86.36 200.66 0)
			(effects
				(font
					(size 1.27 1.27)
					(thickness 0.15)
				)
				(justify left bottom)
				(hide yes)
			)
		)
		(property "Val" "100n"
			(at 63.5 219.7036 90)
			(effects
				(font
					(size 1.27 1.27)
					(thickness 0.15)
				)
				(justify right)
			)
		)
		(property "Voltage" "50V"
			(at 88.9 200.66 0)
			(effects
				(font
					(size 1.27 1.27)
				)
				(justify left bottom)
				(hide yes)
			)
		)
		(property "Dielectric" "X5R"
			(at 91.44 200.66 0)
			(effects
				(font
					(size 1.27 1.27)
				)
				(justify left bottom)
				(hide yes)
			)
		)
		(property "Public" ""
			(at 93.98 200.66 0)
			(effects
				(font
					(size 1.27 1.27)
				)
				(justify left bottom)
				(hide yes)
			)
		)
		(pin "1"
		)
		(pin "2"
		)
		(instances
			(project "polarfire-som"
				(path ""
					(reference "C15")
					(unit 1)
				)
			)
		)
	)
	(symbol
		(lib_id "antmicroCapacitors0402:C_100n_0402")
		(at 119.38 246.38 90)
		(unit 1)
		(exclude_from_sim no)
		(in_bom yes)
		(on_board yes)
		(dnp no)
		(fields_autoplaced yes)
		(property "Reference" "C39"
			(at 121.92 242.5636 90)
			(effects
				(font
					(size 1.27 1.27)
					(thickness 0.15)
				)
				(justify right)
			)
		)
		(property "Value" "C_100n_0402"
			(at 129.54 226.06 0)
			(effects
				(font
					(size 1.27 1.27)
					(thickness 0.15)
				)
				(justify left bottom)
				(hide yes)
			)
		)
		(property "Footprint" "antmicro-footprints:C_0402_1005Metric"
			(at 132.08 226.06 0)
			(effects
				(font
					(size 1.27 1.27)
					(thickness 0.15)
				)
				(justify left bottom)
				(hide yes)
			)
		)
		(property "Datasheet" "https://www.murata.com/products/productdetail?partno=GRM155R61H104KE14%23"
			(at 134.62 226.06 0)
			(effects
				(font
					(size 1.27 1.27)
					(thickness 0.15)
				)
				(justify left bottom)
				(hide yes)
			)
		)
		(property "Description" "SMD Multilayer Ceramic Capacitor, 0.1 µF, 50 V, 0402 [1005 Metric], ± 10%, X5R, GRM Series"
			(at 119.38 246.38 0)
			(effects
				(font
					(size 1.27 1.27)
				)
				(hide yes)
			)
		)
		(property "MPN" "GRM155R61H104KE14D"
			(at 137.16 226.06 0)
			(effects
				(font
					(size 1.27 1.27)
					(thickness 0.15)
				)
				(justify left bottom)
				(hide yes)
			)
		)
		(property "Manufacturer" "Murata"
			(at 139.7 226.06 0)
			(effects
				(font
					(size 1.27 1.27)
					(thickness 0.15)
				)
				(justify left bottom)
				(hide yes)
			)
		)
		(property "License" "Apache-2.0"
			(at 142.24 226.06 0)
			(effects
				(font
					(size 1.27 1.27)
					(thickness 0.15)
				)
				(justify left bottom)
				(hide yes)
			)
		)
		(property "Author" "Antmicro"
			(at 144.78 226.06 0)
			(effects
				(font
					(size 1.27 1.27)
					(thickness 0.15)
				)
				(justify left bottom)
				(hide yes)
			)
		)
		(property "Val" "100n"
			(at 121.92 245.1036 90)
			(effects
				(font
					(size 1.27 1.27)
					(thickness 0.15)
				)
				(justify right)
			)
		)
		(property "Voltage" "50V"
			(at 147.32 226.06 0)
			(effects
				(font
					(size 1.27 1.27)
				)
				(justify left bottom)
				(hide yes)
			)
		)
		(property "Dielectric" "X5R"
			(at 149.86 226.06 0)
			(effects
				(font
					(size 1.27 1.27)
				)
				(justify left bottom)
				(hide yes)
			)
		)
		(property "Public" ""
			(at 152.4 226.06 0)
			(effects
				(font
					(size 1.27 1.27)
				)
				(justify left bottom)
				(hide yes)
			)
		)
		(pin "1"
		)
		(pin "2"
		)
		(instances
			(project "polarfire-som"
				(path ""
					(reference "C39")
					(unit 1)
				)
			)
		)
	)
	(symbol
		(lib_id "antmicroCapacitors0402:C_4n7_0402")
		(at 40.64 168.91 90)
		(unit 1)
		(exclude_from_sim no)
		(in_bom yes)
		(on_board yes)
		(dnp no)
		(fields_autoplaced yes)
		(property "Reference" "C9"
			(at 43.18 165.0936 90)
			(effects
				(font
					(size 1.27 1.27)
					(thickness 0.15)
				)
				(justify right)
			)
		)
		(property "Value" "C_4n7_0402"
			(at 50.8 148.59 0)
			(effects
				(font
					(size 1.27 1.27)
					(thickness 0.15)
				)
				(justify left bottom)
				(hide yes)
			)
		)
		(property "Footprint" "antmicro-footprints:C_0402_1005Metric"
			(at 53.34 148.59 0)
			(effects
				(font
					(size 1.27 1.27)
					(thickness 0.15)
				)
				(justify left bottom)
				(hide yes)
			)
		)
		(property "Datasheet" "https://product.tdk.com/en/search/capacitor/ceramic/mlcc/info?part_no=CGA2B3X7S2A472K050BB"
			(at 55.88 148.59 0)
			(effects
				(font
					(size 1.27 1.27)
					(thickness 0.15)
				)
				(justify left bottom)
				(hide yes)
			)
		)
		(property "Description" "SMD Multilayer Ceramic Capacitor, 4700 pF, 100 V, 0402 [1005 Metric], ± 10%, X7S, CGA"
			(at 40.64 168.91 0)
			(effects
				(font
					(size 1.27 1.27)
				)
				(hide yes)
			)
		)
		(property "MPN" "CGA2B3X7S2A472K050BB"
			(at 58.42 148.59 0)
			(effects
				(font
					(size 1.27 1.27)
					(thickness 0.15)
				)
				(justify left bottom)
				(hide yes)
			)
		)
		(property "Manufacturer" "TDK"
			(at 60.96 148.59 0)
			(effects
				(font
					(size 1.27 1.27)
					(thickness 0.15)
				)
				(justify left bottom)
				(hide yes)
			)
		)
		(property "License" "Apache-2.0"
			(at 63.5 148.59 0)
			(effects
				(font
					(size 1.27 1.27)
					(thickness 0.15)
				)
				(justify left bottom)
				(hide yes)
			)
		)
		(property "Author" "Antmicro"
			(at 66.04 148.59 0)
			(effects
				(font
					(size 1.27 1.27)
					(thickness 0.15)
				)
				(justify left bottom)
				(hide yes)
			)
		)
		(property "Val" "4n7"
			(at 43.18 167.6336 90)
			(effects
				(font
					(size 1.27 1.27)
					(thickness 0.15)
				)
				(justify right)
			)
		)
		(property "Voltage" "25V"
			(at 68.58 148.59 0)
			(effects
				(font
					(size 1.27 1.27)
				)
				(justify left bottom)
				(hide yes)
			)
		)
		(property "Dielectric" "X7R"
			(at 71.12 148.59 0)
			(effects
				(font
					(size 1.27 1.27)
				)
				(justify left bottom)
				(hide yes)
			)
		)
		(property "Public" ""
			(at 73.66 148.59 0)
			(effects
				(font
					(size 1.27 1.27)
				)
				(justify left bottom)
				(hide yes)
			)
		)
		(pin "1"
		)
		(pin "2"
		)
		(instances
			(project "polarfire-som"
				(path ""
					(reference "C9")
					(unit 1)
				)
			)
		)
	)
	(symbol
		(lib_id "antmicropower:GND")
		(at 34.29 199.39 0)
		(unit 1)
		(exclude_from_sim no)
		(in_bom yes)
		(on_board yes)
		(dnp no)
		(property "Reference" "#PWR012"
			(at 43.18 201.93 0)
			(effects
				(font
					(size 1.27 1.27)
					(thickness 0.15)
				)
				(justify left bottom)
				(hide yes)
			)
		)
		(property "Value" "GND"
			(at 34.29 203.2 0)
			(effects
				(font
					(size 1.27 1.27)
					(thickness 0.15)
				)
			)
		)
		(property "Footprint" ""
			(at 43.18 207.01 0)
			(effects
				(font
					(size 1.27 1.27)
					(thickness 0.15)
				)
				(justify left bottom)
				(hide yes)
			)
		)
		(property "Datasheet" ""
			(at 43.18 212.09 0)
			(effects
				(font
					(size 1.27 1.27)
					(thickness 0.15)
				)
				(justify left bottom)
				(hide yes)
			)
		)
		(property "Description" ""
			(at 34.29 199.39 0)
			(effects
				(font
					(size 1.27 1.27)
				)
				(hide yes)
			)
		)
		(property "Author" "Antmicro"
			(at 43.18 207.01 0)
			(effects
				(font
					(size 1.27 1.27)
					(thickness 0.15)
				)
				(justify left bottom)
				(hide yes)
			)
		)
		(property "License" "Apache-2.0"
			(at 43.18 209.55 0)
			(effects
				(font
					(size 1.27 1.27)
					(thickness 0.15)
				)
				(justify left bottom)
				(hide yes)
			)
		)
		(pin "1"
		)
		(instances
			(project "polarfire-som"
				(path ""
					(reference "#PWR012")
					(unit 1)
				)
			)
		)
	)
	(symbol
		(lib_id "antmicropower:+1V05")
		(at 191.77 82.55 90)
		(unit 1)
		(exclude_from_sim no)
		(in_bom yes)
		(on_board yes)
		(dnp no)
		(property "Reference" "#PWR038"
			(at 195.58 82.55 0)
			(effects
				(font
					(size 1.27 1.27)
				)
				(hide yes)
			)
		)
		(property "Value" "+1V05"
			(at 185.42 82.55 90)
			(effects
				(font
					(size 1.27 1.27)
				)
			)
		)
		(property "Footprint" ""
			(at 191.77 82.55 0)
			(effects
				(font
					(size 1.27 1.27)
				)
				(hide yes)
			)
		)
		(property "Datasheet" ""
			(at 191.77 82.55 0)
			(effects
				(font
					(size 1.27 1.27)
				)
				(hide yes)
			)
		)
		(property "Description" ""
			(at 191.77 82.55 0)
			(effects
				(font
					(size 1.27 1.27)
				)
				(hide yes)
			)
		)
		(pin "1"
		)
		(instances
			(project "polarfire-som"
				(path ""
					(reference "#PWR038")
					(unit 1)
				)
			)
		)
	)
	(symbol
		(lib_id "antmicropower:GND")
		(at 182.88 198.12 0)
		(unit 1)
		(exclude_from_sim no)
		(in_bom yes)
		(on_board yes)
		(dnp no)
		(property "Reference" "#PWR031"
			(at 191.77 200.66 0)
			(effects
				(font
					(size 1.27 1.27)
					(thickness 0.15)
				)
				(justify left bottom)
				(hide yes)
			)
		)
		(property "Value" "GND"
			(at 182.88 201.93 0)
			(effects
				(font
					(size 1.27 1.27)
					(thickness 0.15)
				)
			)
		)
		(property "Footprint" ""
			(at 191.77 205.74 0)
			(effects
				(font
					(size 1.27 1.27)
					(thickness 0.15)
				)
				(justify left bottom)
				(hide yes)
			)
		)
		(property "Datasheet" ""
			(at 191.77 210.82 0)
			(effects
				(font
					(size 1.27 1.27)
					(thickness 0.15)
				)
				(justify left bottom)
				(hide yes)
			)
		)
		(property "Description" ""
			(at 182.88 198.12 0)
			(effects
				(font
					(size 1.27 1.27)
				)
				(hide yes)
			)
		)
		(property "Author" "Antmicro"
			(at 191.77 205.74 0)
			(effects
				(font
					(size 1.27 1.27)
					(thickness 0.15)
				)
				(justify left bottom)
				(hide yes)
			)
		)
		(property "License" "Apache-2.0"
			(at 191.77 208.28 0)
			(effects
				(font
					(size 1.27 1.27)
					(thickness 0.15)
				)
				(justify left bottom)
				(hide yes)
			)
		)
		(pin "1"
		)
		(instances
			(project "polarfire-som"
				(path ""
					(reference "#PWR031")
					(unit 1)
				)
			)
		)
	)
	(symbol
		(lib_id "antmicroCapacitors0402:C_100n_0402")
		(at 45.72 246.38 90)
		(unit 1)
		(exclude_from_sim no)
		(in_bom yes)
		(on_board yes)
		(dnp no)
		(fields_autoplaced yes)
		(property "Reference" "C16"
			(at 48.26 242.5636 90)
			(effects
				(font
					(size 1.27 1.27)
					(thickness 0.15)
				)
				(justify right)
			)
		)
		(property "Value" "C_100n_0402"
			(at 55.88 226.06 0)
			(effects
				(font
					(size 1.27 1.27)
					(thickness 0.15)
				)
				(justify left bottom)
				(hide yes)
			)
		)
		(property "Footprint" "antmicro-footprints:C_0402_1005Metric"
			(at 58.42 226.06 0)
			(effects
				(font
					(size 1.27 1.27)
					(thickness 0.15)
				)
				(justify left bottom)
				(hide yes)
			)
		)
		(property "Datasheet" "https://www.murata.com/products/productdetail?partno=GRM155R61H104KE14%23"
			(at 60.96 226.06 0)
			(effects
				(font
					(size 1.27 1.27)
					(thickness 0.15)
				)
				(justify left bottom)
				(hide yes)
			)
		)
		(property "Description" "SMD Multilayer Ceramic Capacitor, 0.1 µF, 50 V, 0402 [1005 Metric], ± 10%, X5R, GRM Series"
			(at 45.72 246.38 0)
			(effects
				(font
					(size 1.27 1.27)
				)
				(hide yes)
			)
		)
		(property "MPN" "GRM155R61H104KE14D"
			(at 63.5 226.06 0)
			(effects
				(font
					(size 1.27 1.27)
					(thickness 0.15)
				)
				(justify left bottom)
				(hide yes)
			)
		)
		(property "Manufacturer" "Murata"
			(at 66.04 226.06 0)
			(effects
				(font
					(size 1.27 1.27)
					(thickness 0.15)
				)
				(justify left bottom)
				(hide yes)
			)
		)
		(property "License" "Apache-2.0"
			(at 68.58 226.06 0)
			(effects
				(font
					(size 1.27 1.27)
					(thickness 0.15)
				)
				(justify left bottom)
				(hide yes)
			)
		)
		(property "Author" "Antmicro"
			(at 71.12 226.06 0)
			(effects
				(font
					(size 1.27 1.27)
					(thickness 0.15)
				)
				(justify left bottom)
				(hide yes)
			)
		)
		(property "Val" "100n"
			(at 48.26 245.1036 90)
			(effects
				(font
					(size 1.27 1.27)
					(thickness 0.15)
				)
				(justify right)
			)
		)
		(property "Voltage" "50V"
			(at 73.66 226.06 0)
			(effects
				(font
					(size 1.27 1.27)
				)
				(justify left bottom)
				(hide yes)
			)
		)
		(property "Dielectric" "X5R"
			(at 76.2 226.06 0)
			(effects
				(font
					(size 1.27 1.27)
				)
				(justify left bottom)
				(hide yes)
			)
		)
		(property "Public" ""
			(at 78.74 226.06 0)
			(effects
				(font
					(size 1.27 1.27)
				)
				(justify left bottom)
				(hide yes)
			)
		)
		(pin "1"
		)
		(pin "2"
		)
		(instances
			(project "polarfire-som"
				(path ""
					(reference "C16")
					(unit 1)
				)
			)
		)
	)
	(symbol
		(lib_id "antmicroCapacitors0402:C_10n_0402")
		(at 50.8 168.91 90)
		(unit 1)
		(exclude_from_sim no)
		(in_bom yes)
		(on_board yes)
		(dnp no)
		(fields_autoplaced yes)
		(property "Reference" "C13"
			(at 53.34 165.0936 90)
			(effects
				(font
					(size 1.27 1.27)
					(thickness 0.15)
				)
				(justify right)
			)
		)
		(property "Value" "C_10n_0402"
			(at 60.96 148.59 0)
			(effects
				(font
					(size 1.27 1.27)
					(thickness 0.15)
				)
				(justify left bottom)
				(hide yes)
			)
		)
		(property "Footprint" "antmicro-footprints:C_0402_1005Metric"
			(at 63.5 148.59 0)
			(effects
				(font
					(size 1.27 1.27)
					(thickness 0.15)
				)
				(justify left bottom)
				(hide yes)
			)
		)
		(property "Datasheet" "https://www.murata.com/products/productdetail?partno=GRM155R71H103KA88%23"
			(at 66.04 148.59 0)
			(effects
				(font
					(size 1.27 1.27)
					(thickness 0.15)
				)
				(justify left bottom)
				(hide yes)
			)
		)
		(property "Description" "SMD Multilayer Ceramic Capacitor, 10000 pF, 50 V, 0402 [1005 Metric], ± 10%, X7R, GRM Series"
			(at 50.8 168.91 0)
			(effects
				(font
					(size 1.27 1.27)
				)
				(hide yes)
			)
		)
		(property "MPN" "GRM155R71H103KA88D"
			(at 68.58 148.59 0)
			(effects
				(font
					(size 1.27 1.27)
					(thickness 0.15)
				)
				(justify left bottom)
				(hide yes)
			)
		)
		(property "Manufacturer" "Murata"
			(at 71.12 148.59 0)
			(effects
				(font
					(size 1.27 1.27)
					(thickness 0.15)
				)
				(justify left bottom)
				(hide yes)
			)
		)
		(property "License" "Apache-2.0"
			(at 73.66 148.59 0)
			(effects
				(font
					(size 1.27 1.27)
					(thickness 0.15)
				)
				(justify left bottom)
				(hide yes)
			)
		)
		(property "Author" "Antmicro"
			(at 76.2 148.59 0)
			(effects
				(font
					(size 1.27 1.27)
					(thickness 0.15)
				)
				(justify left bottom)
				(hide yes)
			)
		)
		(property "Val" "10n"
			(at 53.34 167.6336 90)
			(effects
				(font
					(size 1.27 1.27)
					(thickness 0.15)
				)
				(justify right)
			)
		)
		(property "Voltage" "50V"
			(at 78.74 148.59 0)
			(effects
				(font
					(size 1.27 1.27)
				)
				(justify left bottom)
				(hide yes)
			)
		)
		(property "Dielectric" "X7R"
			(at 81.28 148.59 0)
			(effects
				(font
					(size 1.27 1.27)
				)
				(justify left bottom)
				(hide yes)
			)
		)
		(property "Public" ""
			(at 83.82 148.59 0)
			(effects
				(font
					(size 1.27 1.27)
				)
				(justify left bottom)
				(hide yes)
			)
		)
		(pin "1"
		)
		(pin "2"
		)
		(instances
			(project "polarfire-som"
				(path ""
					(reference "C13")
					(unit 1)
				)
			)
		)
	)
	(symbol
		(lib_id "antmicroCapacitors0402:C_22n_0402")
		(at 146.05 168.91 90)
		(unit 1)
		(exclude_from_sim no)
		(in_bom yes)
		(on_board yes)
		(dnp no)
		(fields_autoplaced yes)
		(property "Reference" "C44"
			(at 148.59 165.0936 90)
			(effects
				(font
					(size 1.27 1.27)
					(thickness 0.15)
				)
				(justify right)
			)
		)
		(property "Value" "C_22n_0402"
			(at 156.21 148.59 0)
			(effects
				(font
					(size 1.27 1.27)
					(thickness 0.15)
				)
				(justify left bottom)
				(hide yes)
			)
		)
		(property "Footprint" "antmicro-footprints:C_0402_1005Metric"
			(at 158.75 148.59 0)
			(effects
				(font
					(size 1.27 1.27)
					(thickness 0.15)
				)
				(justify left bottom)
				(hide yes)
			)
		)
		(property "Datasheet" "https://www.murata.com/products/productdetail?partno=GCM155R71H223MA55%23"
			(at 161.29 148.59 0)
			(effects
				(font
					(size 1.27 1.27)
					(thickness 0.15)
				)
				(justify left bottom)
				(hide yes)
			)
		)
		(property "Description" "SMD Multilayer Ceramic Capacitors, 0.022 µF, 50 V, 20%, 0402 [1005 Metric], X7R"
			(at 146.05 168.91 0)
			(effects
				(font
					(size 1.27 1.27)
				)
				(hide yes)
			)
		)
		(property "MPN" "GCM155R71H223MA55D"
			(at 163.83 148.59 0)
			(effects
				(font
					(size 1.27 1.27)
					(thickness 0.15)
				)
				(justify left bottom)
				(hide yes)
			)
		)
		(property "Manufacturer" "Murata"
			(at 166.37 148.59 0)
			(effects
				(font
					(size 1.27 1.27)
					(thickness 0.15)
				)
				(justify left bottom)
				(hide yes)
			)
		)
		(property "License" "Apache-2.0"
			(at 168.91 148.59 0)
			(effects
				(font
					(size 1.27 1.27)
					(thickness 0.15)
				)
				(justify left bottom)
				(hide yes)
			)
		)
		(property "Author" "Antmicro"
			(at 171.45 148.59 0)
			(effects
				(font
					(size 1.27 1.27)
					(thickness 0.15)
				)
				(justify left bottom)
				(hide yes)
			)
		)
		(property "Val" "22n"
			(at 148.59 167.6336 90)
			(effects
				(font
					(size 1.27 1.27)
					(thickness 0.15)
				)
				(justify right)
			)
		)
		(property "Voltage" ""
			(at 173.99 148.59 0)
			(effects
				(font
					(size 1.27 1.27)
				)
				(justify left bottom)
				(hide yes)
			)
		)
		(property "Dielectric" ""
			(at 176.53 148.59 0)
			(effects
				(font
					(size 1.27 1.27)
				)
				(justify left bottom)
				(hide yes)
			)
		)
		(property "Public" ""
			(at 179.07 148.59 0)
			(effects
				(font
					(size 1.27 1.27)
				)
				(justify left bottom)
				(hide yes)
			)
		)
		(pin "1"
		)
		(pin "2"
		)
		(instances
			(project "polarfire-som"
				(path ""
					(reference "C44")
					(unit 1)
				)
			)
		)
	)
	(symbol
		(lib_id "antmicroCapacitors0603:C_47u_0603")
		(at 182.88 222.25 90)
		(unit 1)
		(exclude_from_sim no)
		(in_bom yes)
		(on_board yes)
		(dnp no)
		(fields_autoplaced yes)
		(property "Reference" "C66"
			(at 185.42 218.4336 90)
			(effects
				(font
					(size 1.27 1.27)
					(thickness 0.15)
				)
				(justify right)
			)
		)
		(property "Value" "C_47u_0603"
			(at 193.04 201.93 0)
			(effects
				(font
					(size 1.27 1.27)
					(thickness 0.15)
				)
				(justify left bottom)
				(hide yes)
			)
		)
		(property "Footprint" "antmicro-footprints:C_0603_1608Metric"
			(at 195.58 201.93 0)
			(effects
				(font
					(size 1.27 1.27)
					(thickness 0.15)
				)
				(justify left bottom)
				(hide yes)
			)
		)
		(property "Datasheet" "https://www.murata.com/products/productdetail?partno=GRM188R60J476ME15%23"
			(at 198.12 201.93 0)
			(effects
				(font
					(size 1.27 1.27)
					(thickness 0.15)
				)
				(justify left bottom)
				(hide yes)
			)
		)
		(property "Description" "SMD Multilayer Ceramic Capacitor, 47 µF, 6.3 V, 0603 [1608 Metric], ± 20%, X5R, GRM Series"
			(at 182.88 222.25 0)
			(effects
				(font
					(size 1.27 1.27)
				)
				(hide yes)
			)
		)
		(property "MPN" "GRM188R60J476ME15D"
			(at 200.66 201.93 0)
			(effects
				(font
					(size 1.27 1.27)
					(thickness 0.15)
				)
				(justify left bottom)
				(hide yes)
			)
		)
		(property "Manufacturer" "Murata"
			(at 203.2 201.93 0)
			(effects
				(font
					(size 1.27 1.27)
					(thickness 0.15)
				)
				(justify left bottom)
				(hide yes)
			)
		)
		(property "License" "Apache-2.0"
			(at 205.74 201.93 0)
			(effects
				(font
					(size 1.27 1.27)
					(thickness 0.15)
				)
				(justify left bottom)
				(hide yes)
			)
		)
		(property "Author" "Antmicro"
			(at 208.28 201.93 0)
			(effects
				(font
					(size 1.27 1.27)
					(thickness 0.15)
				)
				(justify left bottom)
				(hide yes)
			)
		)
		(property "Val" "47u"
			(at 185.42 220.9736 90)
			(effects
				(font
					(size 1.27 1.27)
					(thickness 0.15)
				)
				(justify right)
			)
		)
		(property "Voltage" "50V"
			(at 210.82 201.93 0)
			(effects
				(font
					(size 1.27 1.27)
				)
				(justify left bottom)
				(hide yes)
			)
		)
		(property "Dielectric" "X7R"
			(at 213.36 201.93 0)
			(effects
				(font
					(size 1.27 1.27)
				)
				(justify left bottom)
				(hide yes)
			)
		)
		(property "Capacitance" "47u"
			(at 185.42 220.98 90)
			(effects
				(font
					(size 1.27 1.27)
				)
				(justify right)
				(hide yes)
			)
		)
		(property "Public" ""
			(at 215.9 201.93 0)
			(effects
				(font
					(size 1.27 1.27)
				)
				(justify left bottom)
				(hide yes)
			)
		)
		(pin "1"
		)
		(pin "2"
		)
		(instances
			(project "polarfire-som"
				(path ""
					(reference "C66")
					(unit 1)
				)
			)
		)
	)
	(symbol
		(lib_id "antmicroCapacitors0402:C_10n_0402")
		(at 166.37 276.86 90)
		(unit 1)
		(exclude_from_sim no)
		(in_bom yes)
		(on_board yes)
		(dnp no)
		(fields_autoplaced yes)
		(property "Reference" "C58"
			(at 168.91 273.0436 90)
			(effects
				(font
					(size 1.27 1.27)
					(thickness 0.15)
				)
				(justify right)
			)
		)
		(property "Value" "C_10n_0402"
			(at 176.53 256.54 0)
			(effects
				(font
					(size 1.27 1.27)
					(thickness 0.15)
				)
				(justify left bottom)
				(hide yes)
			)
		)
		(property "Footprint" "antmicro-footprints:C_0402_1005Metric"
			(at 179.07 256.54 0)
			(effects
				(font
					(size 1.27 1.27)
					(thickness 0.15)
				)
				(justify left bottom)
				(hide yes)
			)
		)
		(property "Datasheet" "https://www.murata.com/products/productdetail?partno=GRM155R71H103KA88%23"
			(at 181.61 256.54 0)
			(effects
				(font
					(size 1.27 1.27)
					(thickness 0.15)
				)
				(justify left bottom)
				(hide yes)
			)
		)
		(property "Description" "SMD Multilayer Ceramic Capacitor, 10000 pF, 50 V, 0402 [1005 Metric], ± 10%, X7R, GRM Series"
			(at 166.37 276.86 0)
			(effects
				(font
					(size 1.27 1.27)
				)
				(hide yes)
			)
		)
		(property "MPN" "GRM155R71H103KA88D"
			(at 184.15 256.54 0)
			(effects
				(font
					(size 1.27 1.27)
					(thickness 0.15)
				)
				(justify left bottom)
				(hide yes)
			)
		)
		(property "Manufacturer" "Murata"
			(at 186.69 256.54 0)
			(effects
				(font
					(size 1.27 1.27)
					(thickness 0.15)
				)
				(justify left bottom)
				(hide yes)
			)
		)
		(property "License" "Apache-2.0"
			(at 189.23 256.54 0)
			(effects
				(font
					(size 1.27 1.27)
					(thickness 0.15)
				)
				(justify left bottom)
				(hide yes)
			)
		)
		(property "Author" "Antmicro"
			(at 191.77 256.54 0)
			(effects
				(font
					(size 1.27 1.27)
					(thickness 0.15)
				)
				(justify left bottom)
				(hide yes)
			)
		)
		(property "Val" "10n"
			(at 168.91 275.5836 90)
			(effects
				(font
					(size 1.27 1.27)
					(thickness 0.15)
				)
				(justify right)
			)
		)
		(property "Voltage" "50V"
			(at 194.31 256.54 0)
			(effects
				(font
					(size 1.27 1.27)
				)
				(justify left bottom)
				(hide yes)
			)
		)
		(property "Dielectric" "X7R"
			(at 196.85 256.54 0)
			(effects
				(font
					(size 1.27 1.27)
				)
				(justify left bottom)
				(hide yes)
			)
		)
		(property "Public" ""
			(at 199.39 256.54 0)
			(effects
				(font
					(size 1.27 1.27)
				)
				(justify left bottom)
				(hide yes)
			)
		)
		(pin "1"
		)
		(pin "2"
		)
		(instances
			(project "polarfire-som"
				(path ""
					(reference "C58")
					(unit 1)
				)
			)
		)
	)
	(symbol
		(lib_id "antmicropower:VDDI")
		(at 229.87 80.01 270)
		(unit 1)
		(exclude_from_sim no)
		(in_bom yes)
		(on_board yes)
		(dnp no)
		(fields_autoplaced yes)
		(property "Reference" "#PWR0332"
			(at 226.06 80.01 0)
			(effects
				(font
					(size 1.27 1.27)
				)
				(hide yes)
			)
		)
		(property "Value" "VDD"
			(at 233.68 80.01 90)
			(effects
				(font
					(size 1.27 1.27)
				)
				(justify left)
			)
		)
		(property "Footprint" ""
			(at 229.87 80.01 0)
			(effects
				(font
					(size 1.27 1.27)
				)
				(hide yes)
			)
		)
		(property "Datasheet" ""
			(at 229.87 80.01 0)
			(effects
				(font
					(size 1.27 1.27)
				)
				(hide yes)
			)
		)
		(property "Description" ""
			(at 229.87 80.01 0)
			(effects
				(font
					(size 1.27 1.27)
				)
				(hide yes)
			)
		)
		(pin "1"
		)
		(instances
			(project "polarfire-som"
				(path ""
					(reference "#PWR0332")
					(unit 1)
				)
			)
		)
	)
	(symbol
		(lib_id "antmicroCapacitors0402:C_10n_0402")
		(at 125.73 168.91 90)
		(unit 1)
		(exclude_from_sim no)
		(in_bom yes)
		(on_board yes)
		(dnp no)
		(fields_autoplaced yes)
		(property "Reference" "C64"
			(at 128.27 165.0936 90)
			(effects
				(font
					(size 1.27 1.27)
					(thickness 0.15)
				)
				(justify right)
			)
		)
		(property "Value" "C_10n_0402"
			(at 135.89 148.59 0)
			(effects
				(font
					(size 1.27 1.27)
					(thickness 0.15)
				)
				(justify left bottom)
				(hide yes)
			)
		)
		(property "Footprint" "antmicro-footprints:C_0402_1005Metric"
			(at 138.43 148.59 0)
			(effects
				(font
					(size 1.27 1.27)
					(thickness 0.15)
				)
				(justify left bottom)
				(hide yes)
			)
		)
		(property "Datasheet" "https://www.murata.com/products/productdetail?partno=GRM155R71H103KA88%23"
			(at 140.97 148.59 0)
			(effects
				(font
					(size 1.27 1.27)
					(thickness 0.15)
				)
				(justify left bottom)
				(hide yes)
			)
		)
		(property "Description" "SMD Multilayer Ceramic Capacitor, 10000 pF, 50 V, 0402 [1005 Metric], ± 10%, X7R, GRM Series"
			(at 125.73 168.91 0)
			(effects
				(font
					(size 1.27 1.27)
				)
				(hide yes)
			)
		)
		(property "MPN" "GRM155R71H103KA88D"
			(at 143.51 148.59 0)
			(effects
				(font
					(size 1.27 1.27)
					(thickness 0.15)
				)
				(justify left bottom)
				(hide yes)
			)
		)
		(property "Manufacturer" "Murata"
			(at 146.05 148.59 0)
			(effects
				(font
					(size 1.27 1.27)
					(thickness 0.15)
				)
				(justify left bottom)
				(hide yes)
			)
		)
		(property "License" "Apache-2.0"
			(at 148.59 148.59 0)
			(effects
				(font
					(size 1.27 1.27)
					(thickness 0.15)
				)
				(justify left bottom)
				(hide yes)
			)
		)
		(property "Author" "Antmicro"
			(at 151.13 148.59 0)
			(effects
				(font
					(size 1.27 1.27)
					(thickness 0.15)
				)
				(justify left bottom)
				(hide yes)
			)
		)
		(property "Val" "10n"
			(at 128.27 167.6336 90)
			(effects
				(font
					(size 1.27 1.27)
					(thickness 0.15)
				)
				(justify right)
			)
		)
		(property "Voltage" "50V"
			(at 153.67 148.59 0)
			(effects
				(font
					(size 1.27 1.27)
				)
				(justify left bottom)
				(hide yes)
			)
		)
		(property "Dielectric" "X7R"
			(at 156.21 148.59 0)
			(effects
				(font
					(size 1.27 1.27)
				)
				(justify left bottom)
				(hide yes)
			)
		)
		(property "Public" ""
			(at 158.75 148.59 0)
			(effects
				(font
					(size 1.27 1.27)
				)
				(justify left bottom)
				(hide yes)
			)
		)
		(pin "1"
		)
		(pin "2"
		)
		(instances
			(project "polarfire-som"
				(path ""
					(reference "C64")
					(unit 1)
				)
			)
		)
	)
	(symbol
		(lib_id "antmicroCapacitors0402:C_100n_0402")
		(at 60.96 168.91 90)
		(unit 1)
		(exclude_from_sim no)
		(in_bom yes)
		(on_board yes)
		(dnp no)
		(fields_autoplaced yes)
		(property "Reference" "C17"
			(at 63.5 165.0936 90)
			(effects
				(font
					(size 1.27 1.27)
					(thickness 0.15)
				)
				(justify right)
			)
		)
		(property "Value" "C_100n_0402"
			(at 71.12 148.59 0)
			(effects
				(font
					(size 1.27 1.27)
					(thickness 0.15)
				)
				(justify left bottom)
				(hide yes)
			)
		)
		(property "Footprint" "antmicro-footprints:C_0402_1005Metric"
			(at 73.66 148.59 0)
			(effects
				(font
					(size 1.27 1.27)
					(thickness 0.15)
				)
				(justify left bottom)
				(hide yes)
			)
		)
		(property "Datasheet" "https://www.murata.com/products/productdetail?partno=GRM155R61H104KE14%23"
			(at 76.2 148.59 0)
			(effects
				(font
					(size 1.27 1.27)
					(thickness 0.15)
				)
				(justify left bottom)
				(hide yes)
			)
		)
		(property "Description" "SMD Multilayer Ceramic Capacitor, 0.1 µF, 50 V, 0402 [1005 Metric], ± 10%, X5R, GRM Series"
			(at 60.96 168.91 0)
			(effects
				(font
					(size 1.27 1.27)
				)
				(hide yes)
			)
		)
		(property "MPN" "GRM155R61H104KE14D"
			(at 78.74 148.59 0)
			(effects
				(font
					(size 1.27 1.27)
					(thickness 0.15)
				)
				(justify left bottom)
				(hide yes)
			)
		)
		(property "Manufacturer" "Murata"
			(at 81.28 148.59 0)
			(effects
				(font
					(size 1.27 1.27)
					(thickness 0.15)
				)
				(justify left bottom)
				(hide yes)
			)
		)
		(property "License" "Apache-2.0"
			(at 83.82 148.59 0)
			(effects
				(font
					(size 1.27 1.27)
					(thickness 0.15)
				)
				(justify left bottom)
				(hide yes)
			)
		)
		(property "Author" "Antmicro"
			(at 86.36 148.59 0)
			(effects
				(font
					(size 1.27 1.27)
					(thickness 0.15)
				)
				(justify left bottom)
				(hide yes)
			)
		)
		(property "Val" "100n"
			(at 63.5 167.6336 90)
			(effects
				(font
					(size 1.27 1.27)
					(thickness 0.15)
				)
				(justify right)
			)
		)
		(property "Voltage" "50V"
			(at 88.9 148.59 0)
			(effects
				(font
					(size 1.27 1.27)
				)
				(justify left bottom)
				(hide yes)
			)
		)
		(property "Dielectric" "X5R"
			(at 91.44 148.59 0)
			(effects
				(font
					(size 1.27 1.27)
				)
				(justify left bottom)
				(hide yes)
			)
		)
		(property "Public" ""
			(at 93.98 148.59 0)
			(effects
				(font
					(size 1.27 1.27)
				)
				(justify left bottom)
				(hide yes)
			)
		)
		(pin "1"
		)
		(pin "2"
		)
		(instances
			(project "polarfire-som"
				(path ""
					(reference "C17")
					(unit 1)
				)
			)
		)
	)
	(symbol
		(lib_id "antmicropower:+1V1")
		(at 229.87 90.17 270)
		(unit 1)
		(exclude_from_sim no)
		(in_bom yes)
		(on_board yes)
		(dnp no)
		(property "Reference" "#PWR0233"
			(at 226.06 90.17 0)
			(effects
				(font
					(size 1.27 1.27)
				)
				(hide yes)
			)
		)
		(property "Value" "+1V1"
			(at 234.95 90.17 90)
			(effects
				(font
					(size 1.27 1.27)
				)
			)
		)
		(property "Footprint" ""
			(at 229.87 90.17 0)
			(effects
				(font
					(size 1.27 1.27)
				)
				(hide yes)
			)
		)
		(property "Datasheet" ""
			(at 229.87 90.17 0)
			(effects
				(font
					(size 1.27 1.27)
				)
				(hide yes)
			)
		)
		(property "Description" ""
			(at 229.87 90.17 0)
			(effects
				(font
					(size 1.27 1.27)
				)
				(hide yes)
			)
		)
		(pin "1"
		)
		(instances
			(project "polarfire-som"
				(path ""
					(reference "#PWR0233")
					(unit 1)
				)
			)
		)
	)
	(symbol
		(lib_id "antmicropower:GND")
		(at 139.7 248.92 0)
		(unit 1)
		(exclude_from_sim no)
		(in_bom yes)
		(on_board yes)
		(dnp no)
		(property "Reference" "#PWR026"
			(at 148.59 251.46 0)
			(effects
				(font
					(size 1.27 1.27)
					(thickness 0.15)
				)
				(justify left bottom)
				(hide yes)
			)
		)
		(property "Value" "GND"
			(at 139.7 252.73 0)
			(effects
				(font
					(size 1.27 1.27)
					(thickness 0.15)
				)
			)
		)
		(property "Footprint" ""
			(at 148.59 256.54 0)
			(effects
				(font
					(size 1.27 1.27)
					(thickness 0.15)
				)
				(justify left bottom)
				(hide yes)
			)
		)
		(property "Datasheet" ""
			(at 148.59 261.62 0)
			(effects
				(font
					(size 1.27 1.27)
					(thickness 0.15)
				)
				(justify left bottom)
				(hide yes)
			)
		)
		(property "Description" ""
			(at 139.7 248.92 0)
			(effects
				(font
					(size 1.27 1.27)
				)
				(hide yes)
			)
		)
		(property "Author" "Antmicro"
			(at 148.59 256.54 0)
			(effects
				(font
					(size 1.27 1.27)
					(thickness 0.15)
				)
				(justify left bottom)
				(hide yes)
			)
		)
		(property "License" "Apache-2.0"
			(at 148.59 259.08 0)
			(effects
				(font
					(size 1.27 1.27)
					(thickness 0.15)
				)
				(justify left bottom)
				(hide yes)
			)
		)
		(pin "1"
		)
		(instances
			(project "polarfire-som"
				(path ""
					(reference "#PWR026")
					(unit 1)
				)
			)
		)
	)
	(symbol
		(lib_id "antmicroCapacitors0402:C_100n_0402")
		(at 176.53 276.86 90)
		(unit 1)
		(exclude_from_sim no)
		(in_bom yes)
		(on_board yes)
		(dnp no)
		(fields_autoplaced yes)
		(property "Reference" "C63"
			(at 179.07 273.0436 90)
			(effects
				(font
					(size 1.27 1.27)
					(thickness 0.15)
				)
				(justify right)
			)
		)
		(property "Value" "C_100n_0402"
			(at 186.69 256.54 0)
			(effects
				(font
					(size 1.27 1.27)
					(thickness 0.15)
				)
				(justify left bottom)
				(hide yes)
			)
		)
		(property "Footprint" "antmicro-footprints:C_0402_1005Metric"
			(at 189.23 256.54 0)
			(effects
				(font
					(size 1.27 1.27)
					(thickness 0.15)
				)
				(justify left bottom)
				(hide yes)
			)
		)
		(property "Datasheet" "https://www.murata.com/products/productdetail?partno=GRM155R61H104KE14%23"
			(at 191.77 256.54 0)
			(effects
				(font
					(size 1.27 1.27)
					(thickness 0.15)
				)
				(justify left bottom)
				(hide yes)
			)
		)
		(property "Description" "SMD Multilayer Ceramic Capacitor, 0.1 µF, 50 V, 0402 [1005 Metric], ± 10%, X5R, GRM Series"
			(at 176.53 276.86 0)
			(effects
				(font
					(size 1.27 1.27)
				)
				(hide yes)
			)
		)
		(property "MPN" "GRM155R61H104KE14D"
			(at 194.31 256.54 0)
			(effects
				(font
					(size 1.27 1.27)
					(thickness 0.15)
				)
				(justify left bottom)
				(hide yes)
			)
		)
		(property "Manufacturer" "Murata"
			(at 196.85 256.54 0)
			(effects
				(font
					(size 1.27 1.27)
					(thickness 0.15)
				)
				(justify left bottom)
				(hide yes)
			)
		)
		(property "License" "Apache-2.0"
			(at 199.39 256.54 0)
			(effects
				(font
					(size 1.27 1.27)
					(thickness 0.15)
				)
				(justify left bottom)
				(hide yes)
			)
		)
		(property "Author" "Antmicro"
			(at 201.93 256.54 0)
			(effects
				(font
					(size 1.27 1.27)
					(thickness 0.15)
				)
				(justify left bottom)
				(hide yes)
			)
		)
		(property "Val" "100n"
			(at 179.07 275.5836 90)
			(effects
				(font
					(size 1.27 1.27)
					(thickness 0.15)
				)
				(justify right)
			)
		)
		(property "Voltage" "50V"
			(at 204.47 256.54 0)
			(effects
				(font
					(size 1.27 1.27)
				)
				(justify left bottom)
				(hide yes)
			)
		)
		(property "Dielectric" "X5R"
			(at 207.01 256.54 0)
			(effects
				(font
					(size 1.27 1.27)
				)
				(justify left bottom)
				(hide yes)
			)
		)
		(property "Public" ""
			(at 209.55 256.54 0)
			(effects
				(font
					(size 1.27 1.27)
				)
				(justify left bottom)
				(hide yes)
			)
		)
		(pin "1"
		)
		(pin "2"
		)
		(instances
			(project "polarfire-som"
				(path ""
					(reference "C63")
					(unit 1)
				)
			)
		)
	)
	(symbol
		(lib_id "antmicroCapacitors0402:C_10n_0402")
		(at 111.76 220.98 90)
		(unit 1)
		(exclude_from_sim no)
		(in_bom yes)
		(on_board yes)
		(dnp no)
		(fields_autoplaced yes)
		(property "Reference" "C34"
			(at 114.3 217.1636 90)
			(effects
				(font
					(size 1.27 1.27)
					(thickness 0.15)
				)
				(justify right)
			)
		)
		(property "Value" "C_10n_0402"
			(at 121.92 200.66 0)
			(effects
				(font
					(size 1.27 1.27)
					(thickness 0.15)
				)
				(justify left bottom)
				(hide yes)
			)
		)
		(property "Footprint" "antmicro-footprints:C_0402_1005Metric"
			(at 124.46 200.66 0)
			(effects
				(font
					(size 1.27 1.27)
					(thickness 0.15)
				)
				(justify left bottom)
				(hide yes)
			)
		)
		(property "Datasheet" "https://www.murata.com/products/productdetail?partno=GRM155R71H103KA88%23"
			(at 127 200.66 0)
			(effects
				(font
					(size 1.27 1.27)
					(thickness 0.15)
				)
				(justify left bottom)
				(hide yes)
			)
		)
		(property "Description" "SMD Multilayer Ceramic Capacitor, 10000 pF, 50 V, 0402 [1005 Metric], ± 10%, X7R, GRM Series"
			(at 111.76 220.98 0)
			(effects
				(font
					(size 1.27 1.27)
				)
				(hide yes)
			)
		)
		(property "MPN" "GRM155R71H103KA88D"
			(at 129.54 200.66 0)
			(effects
				(font
					(size 1.27 1.27)
					(thickness 0.15)
				)
				(justify left bottom)
				(hide yes)
			)
		)
		(property "Manufacturer" "Murata"
			(at 132.08 200.66 0)
			(effects
				(font
					(size 1.27 1.27)
					(thickness 0.15)
				)
				(justify left bottom)
				(hide yes)
			)
		)
		(property "License" "Apache-2.0"
			(at 134.62 200.66 0)
			(effects
				(font
					(size 1.27 1.27)
					(thickness 0.15)
				)
				(justify left bottom)
				(hide yes)
			)
		)
		(property "Author" "Antmicro"
			(at 137.16 200.66 0)
			(effects
				(font
					(size 1.27 1.27)
					(thickness 0.15)
				)
				(justify left bottom)
				(hide yes)
			)
		)
		(property "Val" "10n"
			(at 114.3 219.7036 90)
			(effects
				(font
					(size 1.27 1.27)
					(thickness 0.15)
				)
				(justify right)
			)
		)
		(property "Voltage" "50V"
			(at 139.7 200.66 0)
			(effects
				(font
					(size 1.27 1.27)
				)
				(justify left bottom)
				(hide yes)
			)
		)
		(property "Dielectric" "X7R"
			(at 142.24 200.66 0)
			(effects
				(font
					(size 1.27 1.27)
				)
				(justify left bottom)
				(hide yes)
			)
		)
		(property "Public" ""
			(at 144.78 200.66 0)
			(effects
				(font
					(size 1.27 1.27)
				)
				(justify left bottom)
				(hide yes)
			)
		)
		(pin "1"
		)
		(pin "2"
		)
		(instances
			(project "polarfire-som"
				(path ""
					(reference "C34")
					(unit 1)
				)
			)
		)
	)
	(symbol
		(lib_id "antmicropower:+1V8")
		(at 152.4 214.63 0)
		(unit 1)
		(exclude_from_sim no)
		(in_bom yes)
		(on_board yes)
		(dnp no)
		(property "Reference" "#PWR027"
			(at 167.64 217.17 0)
			(effects
				(font
					(size 1.27 1.27)
					(thickness 0.15)
				)
				(justify left bottom)
				(hide yes)
			)
		)
		(property "Value" "+1V8"
			(at 152.4 210.82 0)
			(effects
				(font
					(size 1.27 1.27)
					(thickness 0.15)
				)
			)
		)
		(property "Footprint" ""
			(at 167.64 222.25 0)
			(effects
				(font
					(size 1.27 1.27)
					(thickness 0.15)
				)
				(justify left bottom)
				(hide yes)
			)
		)
		(property "Datasheet" ""
			(at 167.64 224.79 0)
			(effects
				(font
					(size 1.27 1.27)
					(thickness 0.15)
				)
				(justify left bottom)
				(hide yes)
			)
		)
		(property "Description" ""
			(at 152.4 214.63 0)
			(effects
				(font
					(size 1.27 1.27)
				)
				(hide yes)
			)
		)
		(property "Author" "Antmicro"
			(at 167.64 222.25 0)
			(effects
				(font
					(size 1.27 1.27)
					(thickness 0.15)
				)
				(justify left bottom)
				(hide yes)
			)
		)
		(property "License" "Apache-2.0"
			(at 167.64 224.79 0)
			(effects
				(font
					(size 1.27 1.27)
					(thickness 0.15)
				)
				(justify left bottom)
				(hide yes)
			)
		)
		(pin "1"
		)
		(instances
			(project "polarfire-som"
				(path ""
					(reference "#PWR027")
					(unit 1)
				)
			)
		)
	)
	(symbol
		(lib_id "antmicroCapacitors0402:C_4n7_0402")
		(at 86.36 195.58 90)
		(unit 1)
		(exclude_from_sim no)
		(in_bom yes)
		(on_board yes)
		(dnp no)
		(fields_autoplaced yes)
		(property "Reference" "C25"
			(at 88.9 191.7636 90)
			(effects
				(font
					(size 1.27 1.27)
					(thickness 0.15)
				)
				(justify right)
			)
		)
		(property "Value" "C_4n7_0402"
			(at 96.52 175.26 0)
			(effects
				(font
					(size 1.27 1.27)
					(thickness 0.15)
				)
				(justify left bottom)
				(hide yes)
			)
		)
		(property "Footprint" "antmicro-footprints:C_0402_1005Metric"
			(at 99.06 175.26 0)
			(effects
				(font
					(size 1.27 1.27)
					(thickness 0.15)
				)
				(justify left bottom)
				(hide yes)
			)
		)
		(property "Datasheet" "https://product.tdk.com/en/search/capacitor/ceramic/mlcc/info?part_no=CGA2B3X7S2A472K050BB"
			(at 101.6 175.26 0)
			(effects
				(font
					(size 1.27 1.27)
					(thickness 0.15)
				)
				(justify left bottom)
				(hide yes)
			)
		)
		(property "Description" "SMD Multilayer Ceramic Capacitor, 4700 pF, 100 V, 0402 [1005 Metric], ± 10%, X7S, CGA"
			(at 86.36 195.58 0)
			(effects
				(font
					(size 1.27 1.27)
				)
				(hide yes)
			)
		)
		(property "MPN" "CGA2B3X7S2A472K050BB"
			(at 104.14 175.26 0)
			(effects
				(font
					(size 1.27 1.27)
					(thickness 0.15)
				)
				(justify left bottom)
				(hide yes)
			)
		)
		(property "Manufacturer" "TDK"
			(at 106.68 175.26 0)
			(effects
				(font
					(size 1.27 1.27)
					(thickness 0.15)
				)
				(justify left bottom)
				(hide yes)
			)
		)
		(property "License" "Apache-2.0"
			(at 109.22 175.26 0)
			(effects
				(font
					(size 1.27 1.27)
					(thickness 0.15)
				)
				(justify left bottom)
				(hide yes)
			)
		)
		(property "Author" "Antmicro"
			(at 111.76 175.26 0)
			(effects
				(font
					(size 1.27 1.27)
					(thickness 0.15)
				)
				(justify left bottom)
				(hide yes)
			)
		)
		(property "Val" "4n7"
			(at 88.9 194.3036 90)
			(effects
				(font
					(size 1.27 1.27)
					(thickness 0.15)
				)
				(justify right)
			)
		)
		(property "Voltage" "25V"
			(at 114.3 175.26 0)
			(effects
				(font
					(size 1.27 1.27)
				)
				(justify left bottom)
				(hide yes)
			)
		)
		(property "Dielectric" "X7R"
			(at 116.84 175.26 0)
			(effects
				(font
					(size 1.27 1.27)
				)
				(justify left bottom)
				(hide yes)
			)
		)
		(property "Public" ""
			(at 119.38 175.26 0)
			(effects
				(font
					(size 1.27 1.27)
				)
				(justify left bottom)
				(hide yes)
			)
		)
		(pin "1"
		)
		(pin "2"
		)
		(instances
			(project "polarfire-som"
				(path ""
					(reference "C25")
					(unit 1)
				)
			)
		)
	)
	(symbol
		(lib_id "antmicropower:GND")
		(at 182.88 224.79 0)
		(unit 1)
		(exclude_from_sim no)
		(in_bom yes)
		(on_board yes)
		(dnp no)
		(property "Reference" "#PWR032"
			(at 191.77 227.33 0)
			(effects
				(font
					(size 1.27 1.27)
					(thickness 0.15)
				)
				(justify left bottom)
				(hide yes)
			)
		)
		(property "Value" "GND"
			(at 182.88 228.6 0)
			(effects
				(font
					(size 1.27 1.27)
					(thickness 0.15)
				)
			)
		)
		(property "Footprint" ""
			(at 191.77 232.41 0)
			(effects
				(font
					(size 1.27 1.27)
					(thickness 0.15)
				)
				(justify left bottom)
				(hide yes)
			)
		)
		(property "Datasheet" ""
			(at 191.77 237.49 0)
			(effects
				(font
					(size 1.27 1.27)
					(thickness 0.15)
				)
				(justify left bottom)
				(hide yes)
			)
		)
		(property "Description" ""
			(at 182.88 224.79 0)
			(effects
				(font
					(size 1.27 1.27)
				)
				(hide yes)
			)
		)
		(property "Author" "Antmicro"
			(at 191.77 232.41 0)
			(effects
				(font
					(size 1.27 1.27)
					(thickness 0.15)
				)
				(justify left bottom)
				(hide yes)
			)
		)
		(property "License" "Apache-2.0"
			(at 191.77 234.95 0)
			(effects
				(font
					(size 1.27 1.27)
					(thickness 0.15)
				)
				(justify left bottom)
				(hide yes)
			)
		)
		(pin "1"
		)
		(instances
			(project "polarfire-som"
				(path ""
					(reference "#PWR032")
					(unit 1)
				)
			)
		)
	)
	(symbol
		(lib_id "antmicroCapacitors0402:C_4n7_0402")
		(at 78.74 246.38 90)
		(unit 1)
		(exclude_from_sim no)
		(in_bom yes)
		(on_board yes)
		(dnp no)
		(fields_autoplaced yes)
		(property "Reference" "C27"
			(at 81.28 242.5636 90)
			(effects
				(font
					(size 1.27 1.27)
					(thickness 0.15)
				)
				(justify right)
			)
		)
		(property "Value" "C_4n7_0402"
			(at 88.9 226.06 0)
			(effects
				(font
					(size 1.27 1.27)
					(thickness 0.15)
				)
				(justify left bottom)
				(hide yes)
			)
		)
		(property "Footprint" "antmicro-footprints:C_0402_1005Metric"
			(at 91.44 226.06 0)
			(effects
				(font
					(size 1.27 1.27)
					(thickness 0.15)
				)
				(justify left bottom)
				(hide yes)
			)
		)
		(property "Datasheet" "https://product.tdk.com/en/search/capacitor/ceramic/mlcc/info?part_no=CGA2B3X7S2A472K050BB"
			(at 93.98 226.06 0)
			(effects
				(font
					(size 1.27 1.27)
					(thickness 0.15)
				)
				(justify left bottom)
				(hide yes)
			)
		)
		(property "Description" "SMD Multilayer Ceramic Capacitor, 4700 pF, 100 V, 0402 [1005 Metric], ± 10%, X7S, CGA"
			(at 78.74 246.38 0)
			(effects
				(font
					(size 1.27 1.27)
				)
				(hide yes)
			)
		)
		(property "MPN" "CGA2B3X7S2A472K050BB"
			(at 96.52 226.06 0)
			(effects
				(font
					(size 1.27 1.27)
					(thickness 0.15)
				)
				(justify left bottom)
				(hide yes)
			)
		)
		(property "Manufacturer" "TDK"
			(at 99.06 226.06 0)
			(effects
				(font
					(size 1.27 1.27)
					(thickness 0.15)
				)
				(justify left bottom)
				(hide yes)
			)
		)
		(property "License" "Apache-2.0"
			(at 101.6 226.06 0)
			(effects
				(font
					(size 1.27 1.27)
					(thickness 0.15)
				)
				(justify left bottom)
				(hide yes)
			)
		)
		(property "Author" "Antmicro"
			(at 104.14 226.06 0)
			(effects
				(font
					(size 1.27 1.27)
					(thickness 0.15)
				)
				(justify left bottom)
				(hide yes)
			)
		)
		(property "Val" "4n7"
			(at 81.28 245.1036 90)
			(effects
				(font
					(size 1.27 1.27)
					(thickness 0.15)
				)
				(justify right)
			)
		)
		(property "Voltage" "25V"
			(at 106.68 226.06 0)
			(effects
				(font
					(size 1.27 1.27)
				)
				(justify left bottom)
				(hide yes)
			)
		)
		(property "Dielectric" "X7R"
			(at 109.22 226.06 0)
			(effects
				(font
					(size 1.27 1.27)
				)
				(justify left bottom)
				(hide yes)
			)
		)
		(property "Public" ""
			(at 111.76 226.06 0)
			(effects
				(font
					(size 1.27 1.27)
				)
				(justify left bottom)
				(hide yes)
			)
		)
		(pin "1"
		)
		(pin "2"
		)
		(instances
			(project "polarfire-som"
				(path ""
					(reference "C27")
					(unit 1)
				)
			)
		)
	)
	(symbol
		(lib_id "antmicroCapacitors0402:C_1n_0402")
		(at 91.44 220.98 90)
		(unit 1)
		(exclude_from_sim no)
		(in_bom yes)
		(on_board yes)
		(dnp no)
		(fields_autoplaced yes)
		(property "Reference" "C26"
			(at 93.98 217.1636 90)
			(effects
				(font
					(size 1.27 1.27)
					(thickness 0.15)
				)
				(justify right)
			)
		)
		(property "Value" "C_1n_0402"
			(at 101.6 200.66 0)
			(effects
				(font
					(size 1.27 1.27)
					(thickness 0.15)
				)
				(justify left bottom)
				(hide yes)
			)
		)
		(property "Footprint" "antmicro-footprints:C_0402_1005Metric"
			(at 104.14 200.66 0)
			(effects
				(font
					(size 1.27 1.27)
					(thickness 0.15)
				)
				(justify left bottom)
				(hide yes)
			)
		)
		(property "Datasheet" "https://www.murata.com/products/productdetail?partno=GRM1555C1H102JA01%23"
			(at 106.68 200.66 0)
			(effects
				(font
					(size 1.27 1.27)
					(thickness 0.15)
				)
				(justify left bottom)
				(hide yes)
			)
		)
		(property "Description" "SMD Multilayer Ceramic Capacitor, 1000 pF, 50 V, 0402 [1005 Metric], ± 5%, C0G / NP0, GRM Series"
			(at 91.44 220.98 0)
			(effects
				(font
					(size 1.27 1.27)
				)
				(hide yes)
			)
		)
		(property "MPN" "GRM1555C1H102JA01D"
			(at 109.22 200.66 0)
			(effects
				(font
					(size 1.27 1.27)
					(thickness 0.15)
				)
				(justify left bottom)
				(hide yes)
			)
		)
		(property "Manufacturer" "Murata"
			(at 111.76 200.66 0)
			(effects
				(font
					(size 1.27 1.27)
					(thickness 0.15)
				)
				(justify left bottom)
				(hide yes)
			)
		)
		(property "License" "Apache-2.0"
			(at 114.3 200.66 0)
			(effects
				(font
					(size 1.27 1.27)
					(thickness 0.15)
				)
				(justify left bottom)
				(hide yes)
			)
		)
		(property "Author" "Antmicro"
			(at 116.84 200.66 0)
			(effects
				(font
					(size 1.27 1.27)
					(thickness 0.15)
				)
				(justify left bottom)
				(hide yes)
			)
		)
		(property "Val" "1n"
			(at 93.98 219.7036 90)
			(effects
				(font
					(size 1.27 1.27)
					(thickness 0.15)
				)
				(justify right)
			)
		)
		(property "Voltage" "50V"
			(at 119.38 200.66 0)
			(effects
				(font
					(size 1.27 1.27)
				)
				(justify left bottom)
				(hide yes)
			)
		)
		(property "Dielectric" "C0G"
			(at 121.92 200.66 0)
			(effects
				(font
					(size 1.27 1.27)
				)
				(justify left bottom)
				(hide yes)
			)
		)
		(property "Public" ""
			(at 124.46 200.66 0)
			(effects
				(font
					(size 1.27 1.27)
				)
				(justify left bottom)
				(hide yes)
			)
		)
		(pin "1"
		)
		(pin "2"
		)
		(instances
			(project "polarfire-som"
				(path ""
					(reference "C26")
					(unit 1)
				)
			)
		)
	)
	(symbol
		(lib_id "antmicropower:+2V5")
		(at 191.77 80.01 90)
		(unit 1)
		(exclude_from_sim no)
		(in_bom yes)
		(on_board yes)
		(dnp no)
		(property "Reference" "#PWR037"
			(at 195.58 80.01 0)
			(effects
				(font
					(size 1.27 1.27)
				)
				(hide yes)
			)
		)
		(property "Value" "+2V5"
			(at 186.055 80.01 90)
			(effects
				(font
					(size 1.27 1.27)
				)
			)
		)
		(property "Footprint" ""
			(at 191.77 80.01 0)
			(effects
				(font
					(size 1.27 1.27)
				)
				(hide yes)
			)
		)
		(property "Datasheet" ""
			(at 191.77 80.01 0)
			(effects
				(font
					(size 1.27 1.27)
				)
				(hide yes)
			)
		)
		(property "Description" ""
			(at 191.77 80.01 0)
			(effects
				(font
					(size 1.27 1.27)
				)
				(hide yes)
			)
		)
		(pin "1"
		)
		(instances
			(project "polarfire-som"
				(path ""
					(reference "#PWR037")
					(unit 1)
				)
			)
		)
	)
	(symbol
		(lib_id "antmicroCapacitors0402:C_1n_0402")
		(at 152.4 222.25 90)
		(unit 1)
		(exclude_from_sim no)
		(in_bom yes)
		(on_board yes)
		(dnp no)
		(fields_autoplaced yes)
		(property "Reference" "C51"
			(at 154.94 218.4336 90)
			(effects
				(font
					(size 1.27 1.27)
					(thickness 0.15)
				)
				(justify right)
			)
		)
		(property "Value" "C_1n_0402"
			(at 162.56 201.93 0)
			(effects
				(font
					(size 1.27 1.27)
					(thickness 0.15)
				)
				(justify left bottom)
				(hide yes)
			)
		)
		(property "Footprint" "antmicro-footprints:C_0402_1005Metric"
			(at 165.1 201.93 0)
			(effects
				(font
					(size 1.27 1.27)
					(thickness 0.15)
				)
				(justify left bottom)
				(hide yes)
			)
		)
		(property "Datasheet" "https://www.murata.com/products/productdetail?partno=GRM1555C1H102JA01%23"
			(at 167.64 201.93 0)
			(effects
				(font
					(size 1.27 1.27)
					(thickness 0.15)
				)
				(justify left bottom)
				(hide yes)
			)
		)
		(property "Description" "SMD Multilayer Ceramic Capacitor, 1000 pF, 50 V, 0402 [1005 Metric], ± 5%, C0G / NP0, GRM Series"
			(at 152.4 222.25 0)
			(effects
				(font
					(size 1.27 1.27)
				)
				(hide yes)
			)
		)
		(property "MPN" "GRM1555C1H102JA01D"
			(at 170.18 201.93 0)
			(effects
				(font
					(size 1.27 1.27)
					(thickness 0.15)
				)
				(justify left bottom)
				(hide yes)
			)
		)
		(property "Manufacturer" "Murata"
			(at 172.72 201.93 0)
			(effects
				(font
					(size 1.27 1.27)
					(thickness 0.15)
				)
				(justify left bottom)
				(hide yes)
			)
		)
		(property "License" "Apache-2.0"
			(at 175.26 201.93 0)
			(effects
				(font
					(size 1.27 1.27)
					(thickness 0.15)
				)
				(justify left bottom)
				(hide yes)
			)
		)
		(property "Author" "Antmicro"
			(at 177.8 201.93 0)
			(effects
				(font
					(size 1.27 1.27)
					(thickness 0.15)
				)
				(justify left bottom)
				(hide yes)
			)
		)
		(property "Val" "1n"
			(at 154.94 220.9736 90)
			(effects
				(font
					(size 1.27 1.27)
					(thickness 0.15)
				)
				(justify right)
			)
		)
		(property "Voltage" "50V"
			(at 180.34 201.93 0)
			(effects
				(font
					(size 1.27 1.27)
				)
				(justify left bottom)
				(hide yes)
			)
		)
		(property "Dielectric" "C0G"
			(at 182.88 201.93 0)
			(effects
				(font
					(size 1.27 1.27)
				)
				(justify left bottom)
				(hide yes)
			)
		)
		(property "Public" ""
			(at 185.42 201.93 0)
			(effects
				(font
					(size 1.27 1.27)
				)
				(justify left bottom)
				(hide yes)
			)
		)
		(pin "1"
		)
		(pin "2"
		)
		(instances
			(project "polarfire-som"
				(path ""
					(reference "C51")
					(unit 1)
				)
			)
		)
	)
	(symbol
		(lib_id "antmicroCapacitors0402:C_47n_0402")
		(at 166.37 168.91 90)
		(unit 1)
		(exclude_from_sim no)
		(in_bom yes)
		(on_board yes)
		(dnp no)
		(fields_autoplaced yes)
		(property "Reference" "C50"
			(at 168.91 165.0936 90)
			(effects
				(font
					(size 1.27 1.27)
					(thickness 0.15)
				)
				(justify right)
			)
		)
		(property "Value" "C_47n_0402"
			(at 176.53 148.59 0)
			(effects
				(font
					(size 1.27 1.27)
					(thickness 0.15)
				)
				(justify left bottom)
				(hide yes)
			)
		)
		(property "Footprint" "antmicro-footprints:C_0402_1005Metric"
			(at 179.07 148.59 0)
			(effects
				(font
					(size 1.27 1.27)
					(thickness 0.15)
				)
				(justify left bottom)
				(hide yes)
			)
		)
		(property "Datasheet" "https://www.murata.com/en-us/products/productdetail?partno=GRM155R61C473KA01%23"
			(at 181.61 148.59 0)
			(effects
				(font
					(size 1.27 1.27)
					(thickness 0.15)
				)
				(justify left bottom)
				(hide yes)
			)
		)
		(property "Description" "SMD Multilayer Ceramic Capacitor, 47000 pF, 16 V, 0402 [1005 Metric], ± 10%, X5R, MC"
			(at 166.37 168.91 0)
			(effects
				(font
					(size 1.27 1.27)
				)
				(hide yes)
			)
		)
		(property "MPN" "GRM155R61C473KA01D"
			(at 184.15 148.59 0)
			(effects
				(font
					(size 1.27 1.27)
					(thickness 0.15)
				)
				(justify left bottom)
				(hide yes)
			)
		)
		(property "Manufacturer" "Murata"
			(at 186.69 148.59 0)
			(effects
				(font
					(size 1.27 1.27)
					(thickness 0.15)
				)
				(justify left bottom)
				(hide yes)
			)
		)
		(property "License" "Apache-2.0"
			(at 189.23 148.59 0)
			(effects
				(font
					(size 1.27 1.27)
					(thickness 0.15)
				)
				(justify left bottom)
				(hide yes)
			)
		)
		(property "Author" "Antmicro"
			(at 191.77 148.59 0)
			(effects
				(font
					(size 1.27 1.27)
					(thickness 0.15)
				)
				(justify left bottom)
				(hide yes)
			)
		)
		(property "Val" "47n"
			(at 168.91 167.6336 90)
			(effects
				(font
					(size 1.27 1.27)
					(thickness 0.15)
				)
				(justify right)
			)
		)
		(property "Voltage" "10V"
			(at 194.31 148.59 0)
			(effects
				(font
					(size 1.27 1.27)
				)
				(justify left bottom)
				(hide yes)
			)
		)
		(property "Dielectric" "X5R"
			(at 196.85 148.59 0)
			(effects
				(font
					(size 1.27 1.27)
				)
				(justify left bottom)
				(hide yes)
			)
		)
		(property "Public" ""
			(at 199.39 148.59 0)
			(effects
				(font
					(size 1.27 1.27)
				)
				(justify left bottom)
				(hide yes)
			)
		)
		(pin "1"
		)
		(pin "2"
		)
		(instances
			(project "polarfire-som"
				(path ""
					(reference "C50")
					(unit 1)
				)
			)
		)
	)
	(symbol
		(lib_id "antmicroCapacitors0402:C_100n_0402")
		(at 139.7 195.58 90)
		(unit 1)
		(exclude_from_sim no)
		(in_bom yes)
		(on_board yes)
		(dnp no)
		(fields_autoplaced yes)
		(property "Reference" "C46"
			(at 142.24 191.7636 90)
			(effects
				(font
					(size 1.27 1.27)
					(thickness 0.15)
				)
				(justify right)
			)
		)
		(property "Value" "C_100n_0402"
			(at 149.86 175.26 0)
			(effects
				(font
					(size 1.27 1.27)
					(thickness 0.15)
				)
				(justify left bottom)
				(hide yes)
			)
		)
		(property "Footprint" "antmicro-footprints:C_0402_1005Metric"
			(at 152.4 175.26 0)
			(effects
				(font
					(size 1.27 1.27)
					(thickness 0.15)
				)
				(justify left bottom)
				(hide yes)
			)
		)
		(property "Datasheet" "https://www.murata.com/products/productdetail?partno=GRM155R61H104KE14%23"
			(at 154.94 175.26 0)
			(effects
				(font
					(size 1.27 1.27)
					(thickness 0.15)
				)
				(justify left bottom)
				(hide yes)
			)
		)
		(property "Description" "SMD Multilayer Ceramic Capacitor, 0.1 µF, 50 V, 0402 [1005 Metric], ± 10%, X5R, GRM Series"
			(at 139.7 195.58 0)
			(effects
				(font
					(size 1.27 1.27)
				)
				(hide yes)
			)
		)
		(property "MPN" "GRM155R61H104KE14D"
			(at 157.48 175.26 0)
			(effects
				(font
					(size 1.27 1.27)
					(thickness 0.15)
				)
				(justify left bottom)
				(hide yes)
			)
		)
		(property "Manufacturer" "Murata"
			(at 160.02 175.26 0)
			(effects
				(font
					(size 1.27 1.27)
					(thickness 0.15)
				)
				(justify left bottom)
				(hide yes)
			)
		)
		(property "License" "Apache-2.0"
			(at 162.56 175.26 0)
			(effects
				(font
					(size 1.27 1.27)
					(thickness 0.15)
				)
				(justify left bottom)
				(hide yes)
			)
		)
		(property "Author" "Antmicro"
			(at 165.1 175.26 0)
			(effects
				(font
					(size 1.27 1.27)
					(thickness 0.15)
				)
				(justify left bottom)
				(hide yes)
			)
		)
		(property "Val" "100n"
			(at 142.24 194.3036 90)
			(effects
				(font
					(size 1.27 1.27)
					(thickness 0.15)
				)
				(justify right)
			)
		)
		(property "Voltage" "50V"
			(at 167.64 175.26 0)
			(effects
				(font
					(size 1.27 1.27)
				)
				(justify left bottom)
				(hide yes)
			)
		)
		(property "Dielectric" "X5R"
			(at 170.18 175.26 0)
			(effects
				(font
					(size 1.27 1.27)
				)
				(justify left bottom)
				(hide yes)
			)
		)
		(property "Public" ""
			(at 172.72 175.26 0)
			(effects
				(font
					(size 1.27 1.27)
				)
				(justify left bottom)
				(hide yes)
			)
		)
		(pin "1"
		)
		(pin "2"
		)
		(instances
			(project "polarfire-som"
				(path ""
					(reference "C46")
					(unit 1)
				)
			)
		)
	)
	(symbol
		(lib_id "antmicropower:+3V3")
		(at 231.14 82.55 270)
		(unit 1)
		(exclude_from_sim no)
		(in_bom yes)
		(on_board yes)
		(dnp no)
		(property "Reference" "#PWR042"
			(at 231.14 97.79 0)
			(effects
				(font
					(size 1.27 1.27)
					(thickness 0.15)
				)
				(justify left bottom)
				(hide yes)
			)
		)
		(property "Value" "+3V3"
			(at 237.49 82.55 90)
			(effects
				(font
					(size 1.27 1.27)
					(thickness 0.15)
				)
			)
		)
		(property "Footprint" ""
			(at 223.52 97.79 0)
			(effects
				(font
					(size 1.27 1.27)
					(thickness 0.15)
				)
				(justify left bottom)
				(hide yes)
			)
		)
		(property "Datasheet" ""
			(at 220.98 97.79 0)
			(effects
				(font
					(size 1.27 1.27)
					(thickness 0.15)
				)
				(justify left bottom)
				(hide yes)
			)
		)
		(property "Description" ""
			(at 231.14 82.55 0)
			(effects
				(font
					(size 1.27 1.27)
				)
				(hide yes)
			)
		)
		(property "Author" "Antmicro"
			(at 228.6 97.79 0)
			(effects
				(font
					(size 1.27 1.27)
					(thickness 0.15)
				)
				(justify left bottom)
				(hide yes)
			)
		)
		(property "License" "Apache-2.0"
			(at 226.06 97.79 0)
			(effects
				(font
					(size 1.27 1.27)
					(thickness 0.15)
				)
				(justify left bottom)
				(hide yes)
			)
		)
		(pin "1"
		)
		(instances
			(project "polarfire-som"
				(path ""
					(reference "#PWR042")
					(unit 1)
				)
			)
		)
	)
	(symbol
		(lib_id "antmicropower:+1V05")
		(at 95.25 161.29 0)
		(unit 1)
		(exclude_from_sim no)
		(in_bom yes)
		(on_board yes)
		(dnp no)
		(property "Reference" "#PWR022"
			(at 95.25 165.1 0)
			(effects
				(font
					(size 1.27 1.27)
				)
				(hide yes)
			)
		)
		(property "Value" "+1V05"
			(at 95.25 157.48 0)
			(effects
				(font
					(size 1.27 1.27)
				)
			)
		)
		(property "Footprint" ""
			(at 95.25 161.29 0)
			(effects
				(font
					(size 1.27 1.27)
				)
				(hide yes)
			)
		)
		(property "Datasheet" ""
			(at 95.25 161.29 0)
			(effects
				(font
					(size 1.27 1.27)
				)
				(hide yes)
			)
		)
		(property "Description" ""
			(at 95.25 161.29 0)
			(effects
				(font
					(size 1.27 1.27)
				)
				(hide yes)
			)
		)
		(pin "1"
		)
		(instances
			(project "polarfire-som"
				(path ""
					(reference "#PWR022")
					(unit 1)
				)
			)
		)
	)
	(symbol
		(lib_id "antmicropower:GND")
		(at 55.88 248.92 0)
		(unit 1)
		(exclude_from_sim no)
		(in_bom yes)
		(on_board yes)
		(dnp no)
		(property "Reference" "#PWR015"
			(at 64.77 251.46 0)
			(effects
				(font
					(size 1.27 1.27)
					(thickness 0.15)
				)
				(justify left bottom)
				(hide yes)
			)
		)
		(property "Value" "GND"
			(at 55.88 252.73 0)
			(effects
				(font
					(size 1.27 1.27)
					(thickness 0.15)
				)
			)
		)
		(property "Footprint" ""
			(at 64.77 256.54 0)
			(effects
				(font
					(size 1.27 1.27)
					(thickness 0.15)
				)
				(justify left bottom)
				(hide yes)
			)
		)
		(property "Datasheet" ""
			(at 64.77 261.62 0)
			(effects
				(font
					(size 1.27 1.27)
					(thickness 0.15)
				)
				(justify left bottom)
				(hide yes)
			)
		)
		(property "Description" ""
			(at 55.88 248.92 0)
			(effects
				(font
					(size 1.27 1.27)
				)
				(hide yes)
			)
		)
		(property "Author" "Antmicro"
			(at 64.77 256.54 0)
			(effects
				(font
					(size 1.27 1.27)
					(thickness 0.15)
				)
				(justify left bottom)
				(hide yes)
			)
		)
		(property "License" "Apache-2.0"
			(at 64.77 259.08 0)
			(effects
				(font
					(size 1.27 1.27)
					(thickness 0.15)
				)
				(justify left bottom)
				(hide yes)
			)
		)
		(pin "1"
		)
		(instances
			(project "polarfire-som"
				(path ""
					(reference "#PWR015")
					(unit 1)
				)
			)
		)
	)
	(symbol
		(lib_id "antmicropower:+1V8")
		(at 229.87 74.93 270)
		(unit 1)
		(exclude_from_sim no)
		(in_bom yes)
		(on_board yes)
		(dnp no)
		(property "Reference" "#PWR041"
			(at 227.33 90.17 0)
			(effects
				(font
					(size 1.27 1.27)
					(thickness 0.15)
				)
				(justify left bottom)
				(hide yes)
			)
		)
		(property "Value" "+1V8"
			(at 235.585 74.93 90)
			(effects
				(font
					(size 1.27 1.27)
					(thickness 0.15)
				)
			)
		)
		(property "Footprint" ""
			(at 222.25 90.17 0)
			(effects
				(font
					(size 1.27 1.27)
					(thickness 0.15)
				)
				(justify left bottom)
				(hide yes)
			)
		)
		(property "Datasheet" ""
			(at 219.71 90.17 0)
			(effects
				(font
					(size 1.27 1.27)
					(thickness 0.15)
				)
				(justify left bottom)
				(hide yes)
			)
		)
		(property "Description" ""
			(at 229.87 74.93 0)
			(effects
				(font
					(size 1.27 1.27)
				)
				(hide yes)
			)
		)
		(property "Author" "Antmicro"
			(at 222.25 90.17 0)
			(effects
				(font
					(size 1.27 1.27)
					(thickness 0.15)
				)
				(justify left bottom)
				(hide yes)
			)
		)
		(property "License" "Apache-2.0"
			(at 219.71 90.17 0)
			(effects
				(font
					(size 1.27 1.27)
					(thickness 0.15)
				)
				(justify left bottom)
				(hide yes)
			)
		)
		(pin "1"
		)
		(instances
			(project "polarfire-som"
				(path ""
					(reference "#PWR041")
					(unit 1)
				)
			)
		)
	)
	(symbol
		(lib_id "antmicropower:+2V5")
		(at 86.36 187.96 0)
		(unit 1)
		(exclude_from_sim no)
		(in_bom yes)
		(on_board yes)
		(dnp no)
		(property "Reference" "#PWR020"
			(at 86.36 191.77 0)
			(effects
				(font
					(size 1.27 1.27)
				)
				(hide yes)
			)
		)
		(property "Value" "+2V5"
			(at 86.36 184.15 0)
			(effects
				(font
					(size 1.27 1.27)
				)
			)
		)
		(property "Footprint" ""
			(at 86.36 187.96 0)
			(effects
				(font
					(size 1.27 1.27)
				)
				(hide yes)
			)
		)
		(property "Datasheet" ""
			(at 86.36 187.96 0)
			(effects
				(font
					(size 1.27 1.27)
				)
				(hide yes)
			)
		)
		(property "Description" ""
			(at 86.36 187.96 0)
			(effects
				(font
					(size 1.27 1.27)
				)
				(hide yes)
			)
		)
		(pin "1"
		)
		(instances
			(project "polarfire-som"
				(path ""
					(reference "#PWR020")
					(unit 1)
				)
			)
		)
	)
	(symbol
		(lib_id "antmicroCapacitors0402:C_100n_0402")
		(at 135.89 276.86 90)
		(unit 1)
		(exclude_from_sim no)
		(in_bom yes)
		(on_board yes)
		(dnp no)
		(fields_autoplaced yes)
		(property "Reference" "C234"
			(at 138.43 273.0436 90)
			(effects
				(font
					(size 1.27 1.27)
					(thickness 0.15)
				)
				(justify right)
			)
		)
		(property "Value" "C_100n_0402"
			(at 146.05 256.54 0)
			(effects
				(font
					(size 1.27 1.27)
					(thickness 0.15)
				)
				(justify left bottom)
				(hide yes)
			)
		)
		(property "Footprint" "antmicro-footprints:C_0402_1005Metric"
			(at 148.59 256.54 0)
			(effects
				(font
					(size 1.27 1.27)
					(thickness 0.15)
				)
				(justify left bottom)
				(hide yes)
			)
		)
		(property "Datasheet" "https://www.murata.com/products/productdetail?partno=GRM155R61H104KE14%23"
			(at 151.13 256.54 0)
			(effects
				(font
					(size 1.27 1.27)
					(thickness 0.15)
				)
				(justify left bottom)
				(hide yes)
			)
		)
		(property "Description" "SMD Multilayer Ceramic Capacitor, 0.1 µF, 50 V, 0402 [1005 Metric], ± 10%, X5R, GRM Series"
			(at 135.89 276.86 0)
			(effects
				(font
					(size 1.27 1.27)
				)
				(hide yes)
			)
		)
		(property "MPN" "GRM155R61H104KE14D"
			(at 153.67 256.54 0)
			(effects
				(font
					(size 1.27 1.27)
					(thickness 0.15)
				)
				(justify left bottom)
				(hide yes)
			)
		)
		(property "Manufacturer" "Murata"
			(at 156.21 256.54 0)
			(effects
				(font
					(size 1.27 1.27)
					(thickness 0.15)
				)
				(justify left bottom)
				(hide yes)
			)
		)
		(property "License" "Apache-2.0"
			(at 158.75 256.54 0)
			(effects
				(font
					(size 1.27 1.27)
					(thickness 0.15)
				)
				(justify left bottom)
				(hide yes)
			)
		)
		(property "Author" "Antmicro"
			(at 161.29 256.54 0)
			(effects
				(font
					(size 1.27 1.27)
					(thickness 0.15)
				)
				(justify left bottom)
				(hide yes)
			)
		)
		(property "Val" "100n"
			(at 138.43 275.5836 90)
			(effects
				(font
					(size 1.27 1.27)
					(thickness 0.15)
				)
				(justify right)
			)
		)
		(property "Voltage" "50V"
			(at 163.83 256.54 0)
			(effects
				(font
					(size 1.27 1.27)
				)
				(justify left bottom)
				(hide yes)
			)
		)
		(property "Dielectric" "X5R"
			(at 166.37 256.54 0)
			(effects
				(font
					(size 1.27 1.27)
				)
				(justify left bottom)
				(hide yes)
			)
		)
		(property "Public" ""
			(at 168.91 256.54 0)
			(effects
				(font
					(size 1.27 1.27)
				)
				(justify left bottom)
				(hide yes)
			)
		)
		(pin "1"
		)
		(pin "2"
		)
		(instances
			(project "polarfire-som"
				(path ""
					(reference "C234")
					(unit 1)
				)
			)
		)
	)
	(symbol
		(lib_id "antmicropower:PWR_FLAG")
		(at 179.07 96.52 180)
		(unit 1)
		(exclude_from_sim no)
		(in_bom yes)
		(on_board yes)
		(dnp no)
		(property "Reference" "#FLG017"
			(at 179.07 98.425 0)
			(effects
				(font
					(size 1.27 1.27)
				)
				(hide yes)
			)
		)
		(property "Value" "PWR_FLAG"
			(at 179.07 104.14 90)
			(effects
				(font
					(size 1.27 1.27)
				)
			)
		)
		(property "Footprint" ""
			(at 179.07 96.52 0)
			(effects
				(font
					(size 1.27 1.27)
				)
				(hide yes)
			)
		)
		(property "Datasheet" ""
			(at 179.07 96.52 0)
			(effects
				(font
					(size 1.27 1.27)
				)
				(hide yes)
			)
		)
		(property "Description" ""
			(at 179.07 96.52 0)
			(effects
				(font
					(size 1.27 1.27)
				)
				(hide yes)
			)
		)
		(pin "1"
		)
		(instances
			(project "polarfire-som"
				(path ""
					(reference "#FLG017")
					(unit 1)
				)
			)
		)
	)
	(symbol
		(lib_id "antmicroCapacitors0402:C_10u_0402")
		(at 34.29 222.25 90)
		(unit 1)
		(exclude_from_sim no)
		(in_bom yes)
		(on_board yes)
		(dnp no)
		(fields_autoplaced yes)
		(property "Reference" "C11"
			(at 37.465 218.4335 90)
			(effects
				(font
					(size 1.27 1.27)
					(thickness 0.15)
				)
				(justify right)
			)
		)
		(property "Value" "C_10u_0402"
			(at 44.45 201.93 0)
			(effects
				(font
					(size 1.27 1.27)
					(thickness 0.15)
				)
				(justify left bottom)
				(hide yes)
			)
		)
		(property "Footprint" "antmicro-footprints:C_0402_1005Metric"
			(at 46.99 201.93 0)
			(effects
				(font
					(size 1.27 1.27)
					(thickness 0.15)
				)
				(justify left bottom)
				(hide yes)
			)
		)
		(property "Datasheet" "https://www.yageo.com/en/Chart/Download/pdf/CC0402MRX5R5BB106"
			(at 49.53 201.93 0)
			(effects
				(font
					(size 1.27 1.27)
					(thickness 0.15)
				)
				(justify left bottom)
				(hide yes)
			)
		)
		(property "Description" "SMD Multilayer Ceramic Capacitor, 10 µF, 6.3 V, 0402 [1005 Metric], ± 20%, X5R, CC Series"
			(at 34.29 222.25 0)
			(effects
				(font
					(size 1.27 1.27)
				)
				(hide yes)
			)
		)
		(property "MPN" "CC0402MRX5R5BB106"
			(at 52.07 201.93 0)
			(effects
				(font
					(size 1.27 1.27)
					(thickness 0.15)
				)
				(justify left bottom)
				(hide yes)
			)
		)
		(property "Manufacturer" "YAGEO"
			(at 54.61 201.93 0)
			(effects
				(font
					(size 1.27 1.27)
					(thickness 0.15)
				)
				(justify left bottom)
				(hide yes)
			)
		)
		(property "License" "Apache-2.0"
			(at 57.15 201.93 0)
			(effects
				(font
					(size 1.27 1.27)
					(thickness 0.15)
				)
				(justify left bottom)
				(hide yes)
			)
		)
		(property "Author" "Antmicro"
			(at 59.69 201.93 0)
			(effects
				(font
					(size 1.27 1.27)
					(thickness 0.15)
				)
				(justify left bottom)
				(hide yes)
			)
		)
		(property "Val" "10u"
			(at 37.465 220.9735 90)
			(effects
				(font
					(size 1.27 1.27)
					(thickness 0.15)
				)
				(justify right)
			)
		)
		(property "Voltage" ""
			(at 62.23 201.93 0)
			(effects
				(font
					(size 1.27 1.27)
				)
				(justify left bottom)
				(hide yes)
			)
		)
		(property "Dielectric" ""
			(at 64.77 201.93 0)
			(effects
				(font
					(size 1.27 1.27)
				)
				(justify left bottom)
				(hide yes)
			)
		)
		(property "Public" ""
			(at 67.31 201.93 0)
			(effects
				(font
					(size 1.27 1.27)
				)
				(justify left bottom)
				(hide yes)
			)
		)
		(pin "1"
		)
		(pin "2"
		)
		(instances
			(project "polarfire-som"
				(path ""
					(reference "C11")
					(unit 1)
				)
			)
		)
	)
	(symbol
		(lib_id "antmicroCapacitors0402:C_100n_0402")
		(at 129.54 246.38 90)
		(unit 1)
		(exclude_from_sim no)
		(in_bom yes)
		(on_board yes)
		(dnp no)
		(fields_autoplaced yes)
		(property "Reference" "C43"
			(at 132.08 242.5636 90)
			(effects
				(font
					(size 1.27 1.27)
					(thickness 0.15)
				)
				(justify right)
			)
		)
		(property "Value" "C_100n_0402"
			(at 139.7 226.06 0)
			(effects
				(font
					(size 1.27 1.27)
					(thickness 0.15)
				)
				(justify left bottom)
				(hide yes)
			)
		)
		(property "Footprint" "antmicro-footprints:C_0402_1005Metric"
			(at 142.24 226.06 0)
			(effects
				(font
					(size 1.27 1.27)
					(thickness 0.15)
				)
				(justify left bottom)
				(hide yes)
			)
		)
		(property "Datasheet" "https://www.murata.com/products/productdetail?partno=GRM155R61H104KE14%23"
			(at 144.78 226.06 0)
			(effects
				(font
					(size 1.27 1.27)
					(thickness 0.15)
				)
				(justify left bottom)
				(hide yes)
			)
		)
		(property "Description" "SMD Multilayer Ceramic Capacitor, 0.1 µF, 50 V, 0402 [1005 Metric], ± 10%, X5R, GRM Series"
			(at 129.54 246.38 0)
			(effects
				(font
					(size 1.27 1.27)
				)
				(hide yes)
			)
		)
		(property "MPN" "GRM155R61H104KE14D"
			(at 147.32 226.06 0)
			(effects
				(font
					(size 1.27 1.27)
					(thickness 0.15)
				)
				(justify left bottom)
				(hide yes)
			)
		)
		(property "Manufacturer" "Murata"
			(at 149.86 226.06 0)
			(effects
				(font
					(size 1.27 1.27)
					(thickness 0.15)
				)
				(justify left bottom)
				(hide yes)
			)
		)
		(property "License" "Apache-2.0"
			(at 152.4 226.06 0)
			(effects
				(font
					(size 1.27 1.27)
					(thickness 0.15)
				)
				(justify left bottom)
				(hide yes)
			)
		)
		(property "Author" "Antmicro"
			(at 154.94 226.06 0)
			(effects
				(font
					(size 1.27 1.27)
					(thickness 0.15)
				)
				(justify left bottom)
				(hide yes)
			)
		)
		(property "Val" "100n"
			(at 132.08 245.1036 90)
			(effects
				(font
					(size 1.27 1.27)
					(thickness 0.15)
				)
				(justify right)
			)
		)
		(property "Voltage" "50V"
			(at 157.48 226.06 0)
			(effects
				(font
					(size 1.27 1.27)
				)
				(justify left bottom)
				(hide yes)
			)
		)
		(property "Dielectric" "X5R"
			(at 160.02 226.06 0)
			(effects
				(font
					(size 1.27 1.27)
				)
				(justify left bottom)
				(hide yes)
			)
		)
		(property "Public" ""
			(at 162.56 226.06 0)
			(effects
				(font
					(size 1.27 1.27)
				)
				(justify left bottom)
				(hide yes)
			)
		)
		(pin "1"
		)
		(pin "2"
		)
		(instances
			(project "polarfire-som"
				(path ""
					(reference "C43")
					(unit 1)
				)
			)
		)
	)
	(symbol
		(lib_id "antmicropower:+1V05")
		(at 172.72 187.96 0)
		(unit 1)
		(exclude_from_sim no)
		(in_bom yes)
		(on_board yes)
		(dnp no)
		(property "Reference" "#PWR029"
			(at 172.72 191.77 0)
			(effects
				(font
					(size 1.27 1.27)
				)
				(hide yes)
			)
		)
		(property "Value" "+1V05"
			(at 172.72 184.15 0)
			(effects
				(font
					(size 1.27 1.27)
				)
			)
		)
		(property "Footprint" ""
			(at 172.72 187.96 0)
			(effects
				(font
					(size 1.27 1.27)
				)
				(hide yes)
			)
		)
		(property "Datasheet" ""
			(at 172.72 187.96 0)
			(effects
				(font
					(size 1.27 1.27)
				)
				(hide yes)
			)
		)
		(property "Description" ""
			(at 172.72 187.96 0)
			(effects
				(font
					(size 1.27 1.27)
				)
				(hide yes)
			)
		)
		(pin "1"
		)
		(instances
			(project "polarfire-som"
				(path ""
					(reference "#PWR029")
					(unit 1)
				)
			)
		)
	)
	(symbol
		(lib_id "antmicroCapacitors0603:C_47u_0603")
		(at 115.57 276.86 90)
		(unit 1)
		(exclude_from_sim no)
		(in_bom yes)
		(on_board yes)
		(dnp no)
		(fields_autoplaced yes)
		(property "Reference" "C233"
			(at 118.11 273.0436 90)
			(effects
				(font
					(size 1.27 1.27)
					(thickness 0.15)
				)
				(justify right)
			)
		)
		(property "Value" "C_47u_0603"
			(at 125.73 256.54 0)
			(effects
				(font
					(size 1.27 1.27)
					(thickness 0.15)
				)
				(justify left bottom)
				(hide yes)
			)
		)
		(property "Footprint" "antmicro-footprints:C_0603_1608Metric"
			(at 128.27 256.54 0)
			(effects
				(font
					(size 1.27 1.27)
					(thickness 0.15)
				)
				(justify left bottom)
				(hide yes)
			)
		)
		(property "Datasheet" "https://www.murata.com/products/productdetail?partno=GRM188R60J476ME15%23"
			(at 130.81 256.54 0)
			(effects
				(font
					(size 1.27 1.27)
					(thickness 0.15)
				)
				(justify left bottom)
				(hide yes)
			)
		)
		(property "Description" "SMD Multilayer Ceramic Capacitor, 47 µF, 6.3 V, 0603 [1608 Metric], ± 20%, X5R, GRM Series"
			(at 115.57 276.86 0)
			(effects
				(font
					(size 1.27 1.27)
				)
				(hide yes)
			)
		)
		(property "MPN" "GRM188R60J476ME15D"
			(at 133.35 256.54 0)
			(effects
				(font
					(size 1.27 1.27)
					(thickness 0.15)
				)
				(justify left bottom)
				(hide yes)
			)
		)
		(property "Manufacturer" "Murata"
			(at 135.89 256.54 0)
			(effects
				(font
					(size 1.27 1.27)
					(thickness 0.15)
				)
				(justify left bottom)
				(hide yes)
			)
		)
		(property "License" "Apache-2.0"
			(at 138.43 256.54 0)
			(effects
				(font
					(size 1.27 1.27)
					(thickness 0.15)
				)
				(justify left bottom)
				(hide yes)
			)
		)
		(property "Author" "Antmicro"
			(at 140.97 256.54 0)
			(effects
				(font
					(size 1.27 1.27)
					(thickness 0.15)
				)
				(justify left bottom)
				(hide yes)
			)
		)
		(property "Val" "47u"
			(at 118.11 275.5836 90)
			(effects
				(font
					(size 1.27 1.27)
					(thickness 0.15)
				)
				(justify right)
			)
		)
		(property "Voltage" "50V"
			(at 143.51 256.54 0)
			(effects
				(font
					(size 1.27 1.27)
				)
				(justify left bottom)
				(hide yes)
			)
		)
		(property "Dielectric" "X7R"
			(at 146.05 256.54 0)
			(effects
				(font
					(size 1.27 1.27)
				)
				(justify left bottom)
				(hide yes)
			)
		)
		(property "Capacitance" "47u"
			(at 118.11 276.8536 90)
			(effects
				(font
					(size 1.27 1.27)
				)
				(justify right)
				(hide yes)
			)
		)
		(property "Public" ""
			(at 148.59 256.54 0)
			(effects
				(font
					(size 1.27 1.27)
				)
				(justify left bottom)
				(hide yes)
			)
		)
		(pin "1"
		)
		(pin "2"
		)
		(instances
			(project "polarfire-som"
				(path ""
					(reference "C233")
					(unit 1)
				)
			)
		)
	)
	(symbol
		(lib_id "antmicropower:+1V8")
		(at 119.38 187.96 0)
		(unit 1)
		(exclude_from_sim no)
		(in_bom yes)
		(on_board yes)
		(dnp no)
		(property "Reference" "#PWR024"
			(at 134.62 190.5 0)
			(effects
				(font
					(size 1.27 1.27)
					(thickness 0.15)
				)
				(justify left bottom)
				(hide yes)
			)
		)
		(property "Value" "+1V8"
			(at 119.38 184.15 0)
			(effects
				(font
					(size 1.27 1.27)
					(thickness 0.15)
				)
			)
		)
		(property "Footprint" ""
			(at 134.62 195.58 0)
			(effects
				(font
					(size 1.27 1.27)
					(thickness 0.15)
				)
				(justify left bottom)
				(hide yes)
			)
		)
		(property "Datasheet" ""
			(at 134.62 198.12 0)
			(effects
				(font
					(size 1.27 1.27)
					(thickness 0.15)
				)
				(justify left bottom)
				(hide yes)
			)
		)
		(property "Description" ""
			(at 119.38 187.96 0)
			(effects
				(font
					(size 1.27 1.27)
				)
				(hide yes)
			)
		)
		(property "Author" "Antmicro"
			(at 134.62 195.58 0)
			(effects
				(font
					(size 1.27 1.27)
					(thickness 0.15)
				)
				(justify left bottom)
				(hide yes)
			)
		)
		(property "License" "Apache-2.0"
			(at 134.62 198.12 0)
			(effects
				(font
					(size 1.27 1.27)
					(thickness 0.15)
				)
				(justify left bottom)
				(hide yes)
			)
		)
		(pin "1"
		)
		(instances
			(project "polarfire-som"
				(path ""
					(reference "#PWR024")
					(unit 1)
				)
			)
		)
	)
	(symbol
		(lib_id "antmicropower:GND")
		(at 71.12 198.12 0)
		(unit 1)
		(exclude_from_sim no)
		(in_bom yes)
		(on_board yes)
		(dnp no)
		(property "Reference" "#PWR017"
			(at 80.01 200.66 0)
			(effects
				(font
					(size 1.27 1.27)
					(thickness 0.15)
				)
				(justify left bottom)
				(hide yes)
			)
		)
		(property "Value" "GND"
			(at 71.12 201.93 0)
			(effects
				(font
					(size 1.27 1.27)
					(thickness 0.15)
				)
			)
		)
		(property "Footprint" ""
			(at 80.01 205.74 0)
			(effects
				(font
					(size 1.27 1.27)
					(thickness 0.15)
				)
				(justify left bottom)
				(hide yes)
			)
		)
		(property "Datasheet" ""
			(at 80.01 210.82 0)
			(effects
				(font
					(size 1.27 1.27)
					(thickness 0.15)
				)
				(justify left bottom)
				(hide yes)
			)
		)
		(property "Description" ""
			(at 71.12 198.12 0)
			(effects
				(font
					(size 1.27 1.27)
				)
				(hide yes)
			)
		)
		(property "Author" "Antmicro"
			(at 80.01 205.74 0)
			(effects
				(font
					(size 1.27 1.27)
					(thickness 0.15)
				)
				(justify left bottom)
				(hide yes)
			)
		)
		(property "License" "Apache-2.0"
			(at 80.01 208.28 0)
			(effects
				(font
					(size 1.27 1.27)
					(thickness 0.15)
				)
				(justify left bottom)
				(hide yes)
			)
		)
		(pin "1"
		)
		(instances
			(project "polarfire-som"
				(path ""
					(reference "#PWR017")
					(unit 1)
				)
			)
		)
	)
	(symbol
		(lib_id "antmicropower:+1V05")
		(at 191.77 74.93 90)
		(unit 1)
		(exclude_from_sim no)
		(in_bom yes)
		(on_board yes)
		(dnp no)
		(property "Reference" "#PWR035"
			(at 195.58 74.93 0)
			(effects
				(font
					(size 1.27 1.27)
				)
				(hide yes)
			)
		)
		(property "Value" "+1V05"
			(at 185.42 74.93 90)
			(effects
				(font
					(size 1.27 1.27)
				)
			)
		)
		(property "Footprint" ""
			(at 191.77 74.93 0)
			(effects
				(font
					(size 1.27 1.27)
				)
				(hide yes)
			)
		)
		(property "Datasheet" ""
			(at 191.77 74.93 0)
			(effects
				(font
					(size 1.27 1.27)
				)
				(hide yes)
			)
		)
		(property "Description" ""
			(at 191.77 74.93 0)
			(effects
				(font
					(size 1.27 1.27)
				)
				(hide yes)
			)
		)
		(pin "1"
		)
		(instances
			(project "polarfire-som"
				(path ""
					(reference "#PWR035")
					(unit 1)
				)
			)
		)
	)
	(symbol
		(lib_id "antmicropower:VDDAUX")
		(at 135.89 269.24 0)
		(unit 1)
		(exclude_from_sim no)
		(in_bom yes)
		(on_board yes)
		(dnp no)
		(property "Reference" "#PWR0328"
			(at 135.89 273.05 0)
			(effects
				(font
					(size 1.27 1.27)
				)
				(hide yes)
			)
		)
		(property "Value" "VDDAUX"
			(at 135.89 265.43 0)
			(effects
				(font
					(size 1.27 1.27)
				)
			)
		)
		(property "Footprint" ""
			(at 135.89 269.24 0)
			(effects
				(font
					(size 1.27 1.27)
				)
				(hide yes)
			)
		)
		(property "Datasheet" ""
			(at 135.89 269.24 0)
			(effects
				(font
					(size 1.27 1.27)
				)
				(hide yes)
			)
		)
		(property "Description" ""
			(at 135.89 269.24 0)
			(effects
				(font
					(size 1.27 1.27)
				)
				(hide yes)
			)
		)
		(pin "1"
		)
		(instances
			(project "polarfire-som"
				(path ""
					(reference "#PWR0328")
					(unit 1)
				)
			)
		)
	)
	(symbol
		(lib_id "antmicroCapacitors0402:C_3n3_0402")
		(at 30.48 168.91 90)
		(unit 1)
		(exclude_from_sim no)
		(in_bom yes)
		(on_board yes)
		(dnp no)
		(fields_autoplaced yes)
		(property "Reference" "C5"
			(at 33.02 165.0936 90)
			(effects
				(font
					(size 1.27 1.27)
					(thickness 0.15)
				)
				(justify right)
			)
		)
		(property "Value" "C_3n3_0402"
			(at 40.64 148.59 0)
			(effects
				(font
					(size 1.27 1.27)
					(thickness 0.15)
				)
				(justify left bottom)
				(hide yes)
			)
		)
		(property "Footprint" "antmicro-footprints:C_0402_1005Metric"
			(at 43.18 148.59 0)
			(effects
				(font
					(size 1.27 1.27)
					(thickness 0.15)
				)
				(justify left bottom)
				(hide yes)
			)
		)
		(property "Datasheet" "https://www.kemet.com/en/us/capacitors/product/C0402C332K5RAC.html"
			(at 45.72 148.59 0)
			(effects
				(font
					(size 1.27 1.27)
					(thickness 0.15)
				)
				(justify left bottom)
				(hide yes)
			)
		)
		(property "Description" "SMD Multilayer Ceramic Capacitor, 3300 pF, 50 V, 0402 [1005 Metric], ± 10%, X7R, MC"
			(at 30.48 168.91 0)
			(effects
				(font
					(size 1.27 1.27)
				)
				(hide yes)
			)
		)
		(property "MPN" "C0402C332K5RAC"
			(at 48.26 148.59 0)
			(effects
				(font
					(size 1.27 1.27)
					(thickness 0.15)
				)
				(justify left bottom)
				(hide yes)
			)
		)
		(property "Manufacturer" "KEMET"
			(at 50.8 148.59 0)
			(effects
				(font
					(size 1.27 1.27)
					(thickness 0.15)
				)
				(justify left bottom)
				(hide yes)
			)
		)
		(property "License" "Apache-2.0"
			(at 53.34 148.59 0)
			(effects
				(font
					(size 1.27 1.27)
					(thickness 0.15)
				)
				(justify left bottom)
				(hide yes)
			)
		)
		(property "Author" "Antmicro"
			(at 55.88 148.59 0)
			(effects
				(font
					(size 1.27 1.27)
					(thickness 0.15)
				)
				(justify left bottom)
				(hide yes)
			)
		)
		(property "Val" "3n3"
			(at 33.02 167.6336 90)
			(effects
				(font
					(size 1.27 1.27)
					(thickness 0.15)
				)
				(justify right)
			)
		)
		(property "Voltage" "50V"
			(at 58.42 148.59 0)
			(effects
				(font
					(size 1.27 1.27)
				)
				(justify left bottom)
				(hide yes)
			)
		)
		(property "Dielectric" "X7R"
			(at 60.96 148.59 0)
			(effects
				(font
					(size 1.27 1.27)
				)
				(justify left bottom)
				(hide yes)
			)
		)
		(property "Public" ""
			(at 63.5 148.59 0)
			(effects
				(font
					(size 1.27 1.27)
				)
				(justify left bottom)
				(hide yes)
			)
		)
		(pin "2"
		)
		(pin "1"
		)
		(instances
			(project "polarfire-som"
				(path ""
					(reference "C5")
					(unit 1)
				)
			)
		)
	)
	(symbol
		(lib_id "antmicropower:GND")
		(at 34.29 224.79 0)
		(unit 1)
		(exclude_from_sim no)
		(in_bom yes)
		(on_board yes)
		(dnp no)
		(property "Reference" "#PWR013"
			(at 43.18 227.33 0)
			(effects
				(font
					(size 1.27 1.27)
					(thickness 0.15)
				)
				(justify left bottom)
				(hide yes)
			)
		)
		(property "Value" "GND"
			(at 34.29 228.6 0)
			(effects
				(font
					(size 1.27 1.27)
					(thickness 0.15)
				)
			)
		)
		(property "Footprint" ""
			(at 43.18 232.41 0)
			(effects
				(font
					(size 1.27 1.27)
					(thickness 0.15)
				)
				(justify left bottom)
				(hide yes)
			)
		)
		(property "Datasheet" ""
			(at 43.18 237.49 0)
			(effects
				(font
					(size 1.27 1.27)
					(thickness 0.15)
				)
				(justify left bottom)
				(hide yes)
			)
		)
		(property "Description" ""
			(at 34.29 224.79 0)
			(effects
				(font
					(size 1.27 1.27)
				)
				(hide yes)
			)
		)
		(property "Author" "Antmicro"
			(at 43.18 232.41 0)
			(effects
				(font
					(size 1.27 1.27)
					(thickness 0.15)
				)
				(justify left bottom)
				(hide yes)
			)
		)
		(property "License" "Apache-2.0"
			(at 43.18 234.95 0)
			(effects
				(font
					(size 1.27 1.27)
					(thickness 0.15)
				)
				(justify left bottom)
				(hide yes)
			)
		)
		(pin "1"
		)
		(instances
			(project "polarfire-som"
				(path ""
					(reference "#PWR013")
					(unit 1)
				)
			)
		)
	)
	(symbol
		(lib_id "antmicropower:+1V8")
		(at 191.77 77.47 90)
		(unit 1)
		(exclude_from_sim no)
		(in_bom yes)
		(on_board yes)
		(dnp no)
		(property "Reference" "#PWR036"
			(at 194.31 62.23 0)
			(effects
				(font
					(size 1.27 1.27)
					(thickness 0.15)
				)
				(justify left bottom)
				(hide yes)
			)
		)
		(property "Value" "+1V8"
			(at 186.055 77.47 90)
			(effects
				(font
					(size 1.27 1.27)
					(thickness 0.15)
				)
			)
		)
		(property "Footprint" ""
			(at 199.39 62.23 0)
			(effects
				(font
					(size 1.27 1.27)
					(thickness 0.15)
				)
				(justify left bottom)
				(hide yes)
			)
		)
		(property "Datasheet" ""
			(at 201.93 62.23 0)
			(effects
				(font
					(size 1.27 1.27)
					(thickness 0.15)
				)
				(justify left bottom)
				(hide yes)
			)
		)
		(property "Description" ""
			(at 191.77 77.47 0)
			(effects
				(font
					(size 1.27 1.27)
				)
				(hide yes)
			)
		)
		(property "Author" "Antmicro"
			(at 199.39 62.23 0)
			(effects
				(font
					(size 1.27 1.27)
					(thickness 0.15)
				)
				(justify left bottom)
				(hide yes)
			)
		)
		(property "License" "Apache-2.0"
			(at 201.93 62.23 0)
			(effects
				(font
					(size 1.27 1.27)
					(thickness 0.15)
				)
				(justify left bottom)
				(hide yes)
			)
		)
		(pin "1"
		)
		(instances
			(project "polarfire-som"
				(path ""
					(reference "#PWR036")
					(unit 1)
				)
			)
		)
	)
	(symbol
		(lib_id "antmicroCapacitors0402:C_10n_0402")
		(at 105.41 168.91 90)
		(unit 1)
		(exclude_from_sim no)
		(in_bom yes)
		(on_board yes)
		(dnp no)
		(fields_autoplaced yes)
		(property "Reference" "C40"
			(at 107.95 165.0936 90)
			(effects
				(font
					(size 1.27 1.27)
					(thickness 0.15)
				)
				(justify right)
			)
		)
		(property "Value" "C_10n_0402"
			(at 115.57 148.59 0)
			(effects
				(font
					(size 1.27 1.27)
					(thickness 0.15)
				)
				(justify left bottom)
				(hide yes)
			)
		)
		(property "Footprint" "antmicro-footprints:C_0402_1005Metric"
			(at 118.11 148.59 0)
			(effects
				(font
					(size 1.27 1.27)
					(thickness 0.15)
				)
				(justify left bottom)
				(hide yes)
			)
		)
		(property "Datasheet" "https://www.murata.com/products/productdetail?partno=GRM155R71H103KA88%23"
			(at 120.65 148.59 0)
			(effects
				(font
					(size 1.27 1.27)
					(thickness 0.15)
				)
				(justify left bottom)
				(hide yes)
			)
		)
		(property "Description" "SMD Multilayer Ceramic Capacitor, 10000 pF, 50 V, 0402 [1005 Metric], ± 10%, X7R, GRM Series"
			(at 105.41 168.91 0)
			(effects
				(font
					(size 1.27 1.27)
				)
				(hide yes)
			)
		)
		(property "MPN" "GRM155R71H103KA88D"
			(at 123.19 148.59 0)
			(effects
				(font
					(size 1.27 1.27)
					(thickness 0.15)
				)
				(justify left bottom)
				(hide yes)
			)
		)
		(property "Manufacturer" "Murata"
			(at 125.73 148.59 0)
			(effects
				(font
					(size 1.27 1.27)
					(thickness 0.15)
				)
				(justify left bottom)
				(hide yes)
			)
		)
		(property "License" "Apache-2.0"
			(at 128.27 148.59 0)
			(effects
				(font
					(size 1.27 1.27)
					(thickness 0.15)
				)
				(justify left bottom)
				(hide yes)
			)
		)
		(property "Author" "Antmicro"
			(at 130.81 148.59 0)
			(effects
				(font
					(size 1.27 1.27)
					(thickness 0.15)
				)
				(justify left bottom)
				(hide yes)
			)
		)
		(property "Val" "10n"
			(at 107.95 167.6336 90)
			(effects
				(font
					(size 1.27 1.27)
					(thickness 0.15)
				)
				(justify right)
			)
		)
		(property "Voltage" "50V"
			(at 133.35 148.59 0)
			(effects
				(font
					(size 1.27 1.27)
				)
				(justify left bottom)
				(hide yes)
			)
		)
		(property "Dielectric" "X7R"
			(at 135.89 148.59 0)
			(effects
				(font
					(size 1.27 1.27)
				)
				(justify left bottom)
				(hide yes)
			)
		)
		(property "Public" ""
			(at 138.43 148.59 0)
			(effects
				(font
					(size 1.27 1.27)
				)
				(justify left bottom)
				(hide yes)
			)
		)
		(pin "1"
		)
		(pin "2"
		)
		(instances
			(project "polarfire-som"
				(path ""
					(reference "C40")
					(unit 1)
				)
			)
		)
	)
	(symbol
		(lib_id "antmicropower:GND")
		(at 176.53 279.4 0)
		(unit 1)
		(exclude_from_sim no)
		(in_bom yes)
		(on_board yes)
		(dnp no)
		(property "Reference" "#PWR034"
			(at 185.42 281.94 0)
			(effects
				(font
					(size 1.27 1.27)
					(thickness 0.15)
				)
				(justify left bottom)
				(hide yes)
			)
		)
		(property "Value" "GND"
			(at 176.53 283.21 0)
			(effects
				(font
					(size 1.27 1.27)
					(thickness 0.15)
				)
			)
		)
		(property "Footprint" ""
			(at 185.42 287.02 0)
			(effects
				(font
					(size 1.27 1.27)
					(thickness 0.15)
				)
				(justify left bottom)
				(hide yes)
			)
		)
		(property "Datasheet" ""
			(at 185.42 292.1 0)
			(effects
				(font
					(size 1.27 1.27)
					(thickness 0.15)
				)
				(justify left bottom)
				(hide yes)
			)
		)
		(property "Description" ""
			(at 176.53 279.4 0)
			(effects
				(font
					(size 1.27 1.27)
				)
				(hide yes)
			)
		)
		(property "Author" "Antmicro"
			(at 185.42 287.02 0)
			(effects
				(font
					(size 1.27 1.27)
					(thickness 0.15)
				)
				(justify left bottom)
				(hide yes)
			)
		)
		(property "License" "Apache-2.0"
			(at 185.42 289.56 0)
			(effects
				(font
					(size 1.27 1.27)
					(thickness 0.15)
				)
				(justify left bottom)
				(hide yes)
			)
		)
		(pin "1"
		)
		(instances
			(project "polarfire-som"
				(path ""
					(reference "#PWR034")
					(unit 1)
				)
			)
		)
	)
	(symbol
		(lib_id "antmicroCapacitors0402:C_100n_0402")
		(at 105.41 276.86 90)
		(unit 1)
		(exclude_from_sim no)
		(in_bom yes)
		(on_board yes)
		(dnp no)
		(fields_autoplaced yes)
		(property "Reference" "C232"
			(at 107.95 273.0436 90)
			(effects
				(font
					(size 1.27 1.27)
					(thickness 0.15)
				)
				(justify right)
			)
		)
		(property "Value" "C_100n_0402"
			(at 115.57 256.54 0)
			(effects
				(font
					(size 1.27 1.27)
					(thickness 0.15)
				)
				(justify left bottom)
				(hide yes)
			)
		)
		(property "Footprint" "antmicro-footprints:C_0402_1005Metric"
			(at 118.11 256.54 0)
			(effects
				(font
					(size 1.27 1.27)
					(thickness 0.15)
				)
				(justify left bottom)
				(hide yes)
			)
		)
		(property "Datasheet" "https://www.murata.com/products/productdetail?partno=GRM155R61H104KE14%23"
			(at 120.65 256.54 0)
			(effects
				(font
					(size 1.27 1.27)
					(thickness 0.15)
				)
				(justify left bottom)
				(hide yes)
			)
		)
		(property "Description" "SMD Multilayer Ceramic Capacitor, 0.1 µF, 50 V, 0402 [1005 Metric], ± 10%, X5R, GRM Series"
			(at 105.41 276.86 0)
			(effects
				(font
					(size 1.27 1.27)
				)
				(hide yes)
			)
		)
		(property "MPN" "GRM155R61H104KE14D"
			(at 123.19 256.54 0)
			(effects
				(font
					(size 1.27 1.27)
					(thickness 0.15)
				)
				(justify left bottom)
				(hide yes)
			)
		)
		(property "Manufacturer" "Murata"
			(at 125.73 256.54 0)
			(effects
				(font
					(size 1.27 1.27)
					(thickness 0.15)
				)
				(justify left bottom)
				(hide yes)
			)
		)
		(property "License" "Apache-2.0"
			(at 128.27 256.54 0)
			(effects
				(font
					(size 1.27 1.27)
					(thickness 0.15)
				)
				(justify left bottom)
				(hide yes)
			)
		)
		(property "Author" "Antmicro"
			(at 130.81 256.54 0)
			(effects
				(font
					(size 1.27 1.27)
					(thickness 0.15)
				)
				(justify left bottom)
				(hide yes)
			)
		)
		(property "Val" "100n"
			(at 107.95 275.5836 90)
			(effects
				(font
					(size 1.27 1.27)
					(thickness 0.15)
				)
				(justify right)
			)
		)
		(property "Voltage" "50V"
			(at 133.35 256.54 0)
			(effects
				(font
					(size 1.27 1.27)
				)
				(justify left bottom)
				(hide yes)
			)
		)
		(property "Dielectric" "X5R"
			(at 135.89 256.54 0)
			(effects
				(font
					(size 1.27 1.27)
				)
				(justify left bottom)
				(hide yes)
			)
		)
		(property "Public" ""
			(at 138.43 256.54 0)
			(effects
				(font
					(size 1.27 1.27)
				)
				(justify left bottom)
				(hide yes)
			)
		)
		(pin "1"
		)
		(pin "2"
		)
		(instances
			(project "polarfire-som"
				(path ""
					(reference "C232")
					(unit 1)
				)
			)
		)
	)
	(symbol
		(lib_id "antmicropower:GND")
		(at 242.57 100.33 0)
		(unit 1)
		(exclude_from_sim no)
		(in_bom yes)
		(on_board yes)
		(dnp no)
		(property "Reference" "#PWR044"
			(at 251.46 102.87 0)
			(effects
				(font
					(size 1.27 1.27)
					(thickness 0.15)
				)
				(justify left bottom)
				(hide yes)
			)
		)
		(property "Value" "GND"
			(at 242.57 104.14 0)
			(effects
				(font
					(size 1.27 1.27)
					(thickness 0.15)
				)
			)
		)
		(property "Footprint" ""
			(at 251.46 107.95 0)
			(effects
				(font
					(size 1.27 1.27)
					(thickness 0.15)
				)
				(justify left bottom)
				(hide yes)
			)
		)
		(property "Datasheet" ""
			(at 251.46 113.03 0)
			(effects
				(font
					(size 1.27 1.27)
					(thickness 0.15)
				)
				(justify left bottom)
				(hide yes)
			)
		)
		(property "Description" ""
			(at 242.57 100.33 0)
			(effects
				(font
					(size 1.27 1.27)
				)
				(hide yes)
			)
		)
		(property "Author" "Antmicro"
			(at 251.46 107.95 0)
			(effects
				(font
					(size 1.27 1.27)
					(thickness 0.15)
				)
				(justify left bottom)
				(hide yes)
			)
		)
		(property "License" "Apache-2.0"
			(at 251.46 110.49 0)
			(effects
				(font
					(size 1.27 1.27)
					(thickness 0.15)
				)
				(justify left bottom)
				(hide yes)
			)
		)
		(pin "1"
		)
		(instances
			(project "polarfire-som"
				(path ""
					(reference "#PWR044")
					(unit 1)
				)
			)
		)
	)
	(symbol
		(lib_id "antmicropower:VDDI")
		(at 229.87 77.47 270)
		(unit 1)
		(exclude_from_sim no)
		(in_bom yes)
		(on_board yes)
		(dnp no)
		(fields_autoplaced yes)
		(property "Reference" "#PWR0331"
			(at 226.06 77.47 0)
			(effects
				(font
					(size 1.27 1.27)
				)
				(hide yes)
			)
		)
		(property "Value" "VDD"
			(at 233.68 77.47 90)
			(effects
				(font
					(size 1.27 1.27)
				)
				(justify left)
			)
		)
		(property "Footprint" ""
			(at 229.87 77.47 0)
			(effects
				(font
					(size 1.27 1.27)
				)
				(hide yes)
			)
		)
		(property "Datasheet" ""
			(at 229.87 77.47 0)
			(effects
				(font
					(size 1.27 1.27)
				)
				(hide yes)
			)
		)
		(property "Description" ""
			(at 229.87 77.47 0)
			(effects
				(font
					(size 1.27 1.27)
				)
				(hide yes)
			)
		)
		(pin "1"
		)
		(instances
			(project "polarfire-som"
				(path ""
					(reference "#PWR0331")
					(unit 1)
				)
			)
		)
	)
	(symbol
		(lib_id "antmicroCapacitors0603:C_47u_0603")
		(at 106.68 195.58 90)
		(unit 1)
		(exclude_from_sim no)
		(in_bom yes)
		(on_board yes)
		(dnp no)
		(fields_autoplaced yes)
		(property "Reference" "C29"
			(at 109.22 191.7636 90)
			(effects
				(font
					(size 1.27 1.27)
					(thickness 0.15)
				)
				(justify right)
			)
		)
		(property "Value" "C_47u_0603"
			(at 116.84 175.26 0)
			(effects
				(font
					(size 1.27 1.27)
					(thickness 0.15)
				)
				(justify left bottom)
				(hide yes)
			)
		)
		(property "Footprint" "antmicro-footprints:C_0603_1608Metric"
			(at 119.38 175.26 0)
			(effects
				(font
					(size 1.27 1.27)
					(thickness 0.15)
				)
				(justify left bottom)
				(hide yes)
			)
		)
		(property "Datasheet" "https://www.murata.com/products/productdetail?partno=GRM188R60J476ME15%23"
			(at 121.92 175.26 0)
			(effects
				(font
					(size 1.27 1.27)
					(thickness 0.15)
				)
				(justify left bottom)
				(hide yes)
			)
		)
		(property "Description" "SMD Multilayer Ceramic Capacitor, 47 µF, 6.3 V, 0603 [1608 Metric], ± 20%, X5R, GRM Series"
			(at 106.68 195.58 0)
			(effects
				(font
					(size 1.27 1.27)
				)
				(hide yes)
			)
		)
		(property "MPN" "GRM188R60J476ME15D"
			(at 124.46 175.26 0)
			(effects
				(font
					(size 1.27 1.27)
					(thickness 0.15)
				)
				(justify left bottom)
				(hide yes)
			)
		)
		(property "Manufacturer" "Murata"
			(at 127 175.26 0)
			(effects
				(font
					(size 1.27 1.27)
					(thickness 0.15)
				)
				(justify left bottom)
				(hide yes)
			)
		)
		(property "License" "Apache-2.0"
			(at 129.54 175.26 0)
			(effects
				(font
					(size 1.27 1.27)
					(thickness 0.15)
				)
				(justify left bottom)
				(hide yes)
			)
		)
		(property "Author" "Antmicro"
			(at 132.08 175.26 0)
			(effects
				(font
					(size 1.27 1.27)
					(thickness 0.15)
				)
				(justify left bottom)
				(hide yes)
			)
		)
		(property "Val" "47u"
			(at 109.22 194.3036 90)
			(effects
				(font
					(size 1.27 1.27)
					(thickness 0.15)
				)
				(justify right)
			)
		)
		(property "Voltage" "50V"
			(at 134.62 175.26 0)
			(effects
				(font
					(size 1.27 1.27)
				)
				(justify left bottom)
				(hide yes)
			)
		)
		(property "Dielectric" "X7R"
			(at 137.16 175.26 0)
			(effects
				(font
					(size 1.27 1.27)
				)
				(justify left bottom)
				(hide yes)
			)
		)
		(property "Capacitance" "47u"
			(at 109.22 194.31 90)
			(effects
				(font
					(size 1.27 1.27)
				)
				(justify right)
				(hide yes)
			)
		)
		(property "Public" ""
			(at 139.7 175.26 0)
			(effects
				(font
					(size 1.27 1.27)
				)
				(justify left bottom)
				(hide yes)
			)
		)
		(pin "1"
		)
		(pin "2"
		)
		(instances
			(project "polarfire-som"
				(path ""
					(reference "C29")
					(unit 1)
				)
			)
		)
	)
	(symbol
		(lib_id "antmicropower:PWR_FLAG")
		(at 248.92 92.71 270)
		(unit 1)
		(exclude_from_sim no)
		(in_bom yes)
		(on_board yes)
		(dnp no)
		(property "Reference" "#FLG014"
			(at 250.825 92.71 0)
			(effects
				(font
					(size 1.27 1.27)
				)
				(hide yes)
			)
		)
		(property "Value" "PWR_FLAG"
			(at 256.54 92.71 90)
			(effects
				(font
					(size 1.27 1.27)
				)
			)
		)
		(property "Footprint" ""
			(at 248.92 92.71 0)
			(effects
				(font
					(size 1.27 1.27)
				)
				(hide yes)
			)
		)
		(property "Datasheet" ""
			(at 248.92 92.71 0)
			(effects
				(font
					(size 1.27 1.27)
				)
				(hide yes)
			)
		)
		(property "Description" ""
			(at 248.92 92.71 0)
			(effects
				(font
					(size 1.27 1.27)
				)
				(hide yes)
			)
		)
		(pin "1"
		)
		(instances
			(project "polarfire-som"
				(path ""
					(reference "#FLG014")
					(unit 1)
				)
			)
		)
	)
	(symbol
		(lib_id "antmicropower:VDDI")
		(at 60.96 214.63 0)
		(unit 1)
		(exclude_from_sim no)
		(in_bom yes)
		(on_board yes)
		(dnp no)
		(fields_autoplaced yes)
		(property "Reference" "#PWR0325"
			(at 60.96 218.44 0)
			(effects
				(font
					(size 1.27 1.27)
				)
				(hide yes)
			)
		)
		(property "Value" "VDD"
			(at 60.96 210.185 0)
			(effects
				(font
					(size 1.27 1.27)
				)
			)
		)
		(property "Footprint" ""
			(at 60.96 214.63 0)
			(effects
				(font
					(size 1.27 1.27)
				)
				(hide yes)
			)
		)
		(property "Datasheet" ""
			(at 60.96 214.63 0)
			(effects
				(font
					(size 1.27 1.27)
				)
				(hide yes)
			)
		)
		(property "Description" ""
			(at 60.96 214.63 0)
			(effects
				(font
					(size 1.27 1.27)
				)
				(hide yes)
			)
		)
		(pin "1"
		)
		(instances
			(project "polarfire-som"
				(path ""
					(reference "#PWR0325")
					(unit 1)
				)
			)
		)
	)
	(symbol
		(lib_id "antmicroCapacitors0402:C_100n_0402")
		(at 121.92 220.98 90)
		(unit 1)
		(exclude_from_sim no)
		(in_bom yes)
		(on_board yes)
		(dnp no)
		(fields_autoplaced yes)
		(property "Reference" "C37"
			(at 124.46 217.1636 90)
			(effects
				(font
					(size 1.27 1.27)
					(thickness 0.15)
				)
				(justify right)
			)
		)
		(property "Value" "C_100n_0402"
			(at 132.08 200.66 0)
			(effects
				(font
					(size 1.27 1.27)
					(thickness 0.15)
				)
				(justify left bottom)
				(hide yes)
			)
		)
		(property "Footprint" "antmicro-footprints:C_0402_1005Metric"
			(at 134.62 200.66 0)
			(effects
				(font
					(size 1.27 1.27)
					(thickness 0.15)
				)
				(justify left bottom)
				(hide yes)
			)
		)
		(property "Datasheet" "https://www.murata.com/products/productdetail?partno=GRM155R61H104KE14%23"
			(at 137.16 200.66 0)
			(effects
				(font
					(size 1.27 1.27)
					(thickness 0.15)
				)
				(justify left bottom)
				(hide yes)
			)
		)
		(property "Description" "SMD Multilayer Ceramic Capacitor, 0.1 µF, 50 V, 0402 [1005 Metric], ± 10%, X5R, GRM Series"
			(at 121.92 220.98 0)
			(effects
				(font
					(size 1.27 1.27)
				)
				(hide yes)
			)
		)
		(property "MPN" "GRM155R61H104KE14D"
			(at 139.7 200.66 0)
			(effects
				(font
					(size 1.27 1.27)
					(thickness 0.15)
				)
				(justify left bottom)
				(hide yes)
			)
		)
		(property "Manufacturer" "Murata"
			(at 142.24 200.66 0)
			(effects
				(font
					(size 1.27 1.27)
					(thickness 0.15)
				)
				(justify left bottom)
				(hide yes)
			)
		)
		(property "License" "Apache-2.0"
			(at 144.78 200.66 0)
			(effects
				(font
					(size 1.27 1.27)
					(thickness 0.15)
				)
				(justify left bottom)
				(hide yes)
			)
		)
		(property "Author" "Antmicro"
			(at 147.32 200.66 0)
			(effects
				(font
					(size 1.27 1.27)
					(thickness 0.15)
				)
				(justify left bottom)
				(hide yes)
			)
		)
		(property "Val" "100n"
			(at 124.46 219.7036 90)
			(effects
				(font
					(size 1.27 1.27)
					(thickness 0.15)
				)
				(justify right)
			)
		)
		(property "Voltage" "50V"
			(at 149.86 200.66 0)
			(effects
				(font
					(size 1.27 1.27)
				)
				(justify left bottom)
				(hide yes)
			)
		)
		(property "Dielectric" "X5R"
			(at 152.4 200.66 0)
			(effects
				(font
					(size 1.27 1.27)
				)
				(justify left bottom)
				(hide yes)
			)
		)
		(property "Public" ""
			(at 154.94 200.66 0)
			(effects
				(font
					(size 1.27 1.27)
				)
				(justify left bottom)
				(hide yes)
			)
		)
		(pin "1"
		)
		(pin "2"
		)
		(instances
			(project "polarfire-som"
				(path ""
					(reference "C37")
					(unit 1)
				)
			)
		)
	)
	(symbol
		(lib_id "antmicroCapacitors0402:C_100n_0402")
		(at 109.22 246.38 90)
		(unit 1)
		(exclude_from_sim no)
		(in_bom yes)
		(on_board yes)
		(dnp no)
		(fields_autoplaced yes)
		(property "Reference" "C31"
			(at 111.76 242.5636 90)
			(effects
				(font
					(size 1.27 1.27)
					(thickness 0.15)
				)
				(justify right)
			)
		)
		(property "Value" "C_100n_0402"
			(at 119.38 226.06 0)
			(effects
				(font
					(size 1.27 1.27)
					(thickness 0.15)
				)
				(justify left bottom)
				(hide yes)
			)
		)
		(property "Footprint" "antmicro-footprints:C_0402_1005Metric"
			(at 121.92 226.06 0)
			(effects
				(font
					(size 1.27 1.27)
					(thickness 0.15)
				)
				(justify left bottom)
				(hide yes)
			)
		)
		(property "Datasheet" "https://www.murata.com/products/productdetail?partno=GRM155R61H104KE14%23"
			(at 124.46 226.06 0)
			(effects
				(font
					(size 1.27 1.27)
					(thickness 0.15)
				)
				(justify left bottom)
				(hide yes)
			)
		)
		(property "Description" "SMD Multilayer Ceramic Capacitor, 0.1 µF, 50 V, 0402 [1005 Metric], ± 10%, X5R, GRM Series"
			(at 109.22 246.38 0)
			(effects
				(font
					(size 1.27 1.27)
				)
				(hide yes)
			)
		)
		(property "MPN" "GRM155R61H104KE14D"
			(at 127 226.06 0)
			(effects
				(font
					(size 1.27 1.27)
					(thickness 0.15)
				)
				(justify left bottom)
				(hide yes)
			)
		)
		(property "Manufacturer" "Murata"
			(at 129.54 226.06 0)
			(effects
				(font
					(size 1.27 1.27)
					(thickness 0.15)
				)
				(justify left bottom)
				(hide yes)
			)
		)
		(property "License" "Apache-2.0"
			(at 132.08 226.06 0)
			(effects
				(font
					(size 1.27 1.27)
					(thickness 0.15)
				)
				(justify left bottom)
				(hide yes)
			)
		)
		(property "Author" "Antmicro"
			(at 134.62 226.06 0)
			(effects
				(font
					(size 1.27 1.27)
					(thickness 0.15)
				)
				(justify left bottom)
				(hide yes)
			)
		)
		(property "Val" "100n"
			(at 111.76 245.1036 90)
			(effects
				(font
					(size 1.27 1.27)
					(thickness 0.15)
				)
				(justify right)
			)
		)
		(property "Voltage" "50V"
			(at 137.16 226.06 0)
			(effects
				(font
					(size 1.27 1.27)
				)
				(justify left bottom)
				(hide yes)
			)
		)
		(property "Dielectric" "X5R"
			(at 139.7 226.06 0)
			(effects
				(font
					(size 1.27 1.27)
				)
				(justify left bottom)
				(hide yes)
			)
		)
		(property "Public" ""
			(at 142.24 226.06 0)
			(effects
				(font
					(size 1.27 1.27)
				)
				(justify left bottom)
				(hide yes)
			)
		)
		(pin "1"
		)
		(pin "2"
		)
		(instances
			(project "polarfire-som"
				(path ""
					(reference "C31")
					(unit 1)
				)
			)
		)
	)
	(symbol
		(lib_id "antmicropower:PWR_FLAG")
		(at 182.88 238.76 0)
		(unit 1)
		(exclude_from_sim no)
		(in_bom yes)
		(on_board yes)
		(dnp no)
		(property "Reference" "#FLG025"
			(at 182.88 236.855 0)
			(effects
				(font
					(size 1.27 1.27)
				)
				(hide yes)
			)
		)
		(property "Value" "PWR_FLAG"
			(at 183.134 234.95 0)
			(effects
				(font
					(size 1.27 1.27)
				)
			)
		)
		(property "Footprint" ""
			(at 182.88 238.76 0)
			(effects
				(font
					(size 1.27 1.27)
				)
				(hide yes)
			)
		)
		(property "Datasheet" ""
			(at 182.88 238.76 0)
			(effects
				(font
					(size 1.27 1.27)
				)
				(hide yes)
			)
		)
		(property "Description" ""
			(at 182.88 238.76 0)
			(effects
				(font
					(size 1.27 1.27)
				)
				(hide yes)
			)
		)
		(pin "1"
		)
		(instances
			(project "polarfire-som"
				(path ""
					(reference "#FLG025")
					(unit 1)
				)
			)
		)
	)
	(symbol
		(lib_id "antmicroCapacitors0402:C_10u_0402")
		(at 71.12 195.58 90)
		(unit 1)
		(exclude_from_sim no)
		(in_bom yes)
		(on_board yes)
		(dnp no)
		(fields_autoplaced yes)
		(property "Reference" "C22"
			(at 74.295 191.7635 90)
			(effects
				(font
					(size 1.27 1.27)
					(thickness 0.15)
				)
				(justify right)
			)
		)
		(property "Value" "C_10u_0402"
			(at 81.28 175.26 0)
			(effects
				(font
					(size 1.27 1.27)
					(thickness 0.15)
				)
				(justify left bottom)
				(hide yes)
			)
		)
		(property "Footprint" "antmicro-footprints:C_0402_1005Metric"
			(at 83.82 175.26 0)
			(effects
				(font
					(size 1.27 1.27)
					(thickness 0.15)
				)
				(justify left bottom)
				(hide yes)
			)
		)
		(property "Datasheet" "https://www.yageo.com/en/Chart/Download/pdf/CC0402MRX5R5BB106"
			(at 86.36 175.26 0)
			(effects
				(font
					(size 1.27 1.27)
					(thickness 0.15)
				)
				(justify left bottom)
				(hide yes)
			)
		)
		(property "Description" "SMD Multilayer Ceramic Capacitor, 10 µF, 6.3 V, 0402 [1005 Metric], ± 20%, X5R, CC Series"
			(at 71.12 195.58 0)
			(effects
				(font
					(size 1.27 1.27)
				)
				(hide yes)
			)
		)
		(property "MPN" "CC0402MRX5R5BB106"
			(at 88.9 175.26 0)
			(effects
				(font
					(size 1.27 1.27)
					(thickness 0.15)
				)
				(justify left bottom)
				(hide yes)
			)
		)
		(property "Manufacturer" "YAGEO"
			(at 91.44 175.26 0)
			(effects
				(font
					(size 1.27 1.27)
					(thickness 0.15)
				)
				(justify left bottom)
				(hide yes)
			)
		)
		(property "License" "Apache-2.0"
			(at 93.98 175.26 0)
			(effects
				(font
					(size 1.27 1.27)
					(thickness 0.15)
				)
				(justify left bottom)
				(hide yes)
			)
		)
		(property "Author" "Antmicro"
			(at 96.52 175.26 0)
			(effects
				(font
					(size 1.27 1.27)
					(thickness 0.15)
				)
				(justify left bottom)
				(hide yes)
			)
		)
		(property "Val" "10u"
			(at 74.295 194.3035 90)
			(effects
				(font
					(size 1.27 1.27)
					(thickness 0.15)
				)
				(justify right)
			)
		)
		(property "Voltage" ""
			(at 99.06 175.26 0)
			(effects
				(font
					(size 1.27 1.27)
				)
				(justify left bottom)
				(hide yes)
			)
		)
		(property "Dielectric" ""
			(at 101.6 175.26 0)
			(effects
				(font
					(size 1.27 1.27)
				)
				(justify left bottom)
				(hide yes)
			)
		)
		(property "Public" ""
			(at 104.14 175.26 0)
			(effects
				(font
					(size 1.27 1.27)
				)
				(justify left bottom)
				(hide yes)
			)
		)
		(pin "1"
		)
		(pin "2"
		)
		(instances
			(project "polarfire-som"
				(path ""
					(reference "C22")
					(unit 1)
				)
			)
		)
	)
	(symbol
		(lib_id "antmicroCapacitors0603:C_47u_0603")
		(at 146.05 276.86 90)
		(unit 1)
		(exclude_from_sim no)
		(in_bom yes)
		(on_board yes)
		(dnp no)
		(fields_autoplaced yes)
		(property "Reference" "C262"
			(at 148.59 273.0436 90)
			(effects
				(font
					(size 1.27 1.27)
					(thickness 0.15)
				)
				(justify right)
			)
		)
		(property "Value" "C_47u_0603"
			(at 156.21 256.54 0)
			(effects
				(font
					(size 1.27 1.27)
					(thickness 0.15)
				)
				(justify left bottom)
				(hide yes)
			)
		)
		(property "Footprint" "antmicro-footprints:C_0603_1608Metric"
			(at 158.75 256.54 0)
			(effects
				(font
					(size 1.27 1.27)
					(thickness 0.15)
				)
				(justify left bottom)
				(hide yes)
			)
		)
		(property "Datasheet" "https://www.murata.com/products/productdetail?partno=GRM188R60J476ME15%23"
			(at 161.29 256.54 0)
			(effects
				(font
					(size 1.27 1.27)
					(thickness 0.15)
				)
				(justify left bottom)
				(hide yes)
			)
		)
		(property "Description" "SMD Multilayer Ceramic Capacitor, 47 µF, 6.3 V, 0603 [1608 Metric], ± 20%, X5R, GRM Series"
			(at 146.05 276.86 0)
			(effects
				(font
					(size 1.27 1.27)
				)
				(hide yes)
			)
		)
		(property "MPN" "GRM188R60J476ME15D"
			(at 163.83 256.54 0)
			(effects
				(font
					(size 1.27 1.27)
					(thickness 0.15)
				)
				(justify left bottom)
				(hide yes)
			)
		)
		(property "Manufacturer" "Murata"
			(at 166.37 256.54 0)
			(effects
				(font
					(size 1.27 1.27)
					(thickness 0.15)
				)
				(justify left bottom)
				(hide yes)
			)
		)
		(property "License" "Apache-2.0"
			(at 168.91 256.54 0)
			(effects
				(font
					(size 1.27 1.27)
					(thickness 0.15)
				)
				(justify left bottom)
				(hide yes)
			)
		)
		(property "Author" "Antmicro"
			(at 171.45 256.54 0)
			(effects
				(font
					(size 1.27 1.27)
					(thickness 0.15)
				)
				(justify left bottom)
				(hide yes)
			)
		)
		(property "Val" "47u"
			(at 148.59 275.5836 90)
			(effects
				(font
					(size 1.27 1.27)
					(thickness 0.15)
				)
				(justify right)
			)
		)
		(property "Voltage" "50V"
			(at 173.99 256.54 0)
			(effects
				(font
					(size 1.27 1.27)
				)
				(justify left bottom)
				(hide yes)
			)
		)
		(property "Dielectric" "X7R"
			(at 176.53 256.54 0)
			(effects
				(font
					(size 1.27 1.27)
				)
				(justify left bottom)
				(hide yes)
			)
		)
		(property "Capacitance" "47u"
			(at 148.59 276.8536 90)
			(effects
				(font
					(size 1.27 1.27)
				)
				(justify right)
				(hide yes)
			)
		)
		(property "Public" ""
			(at 179.07 256.54 0)
			(effects
				(font
					(size 1.27 1.27)
				)
				(justify left bottom)
				(hide yes)
			)
		)
		(pin "1"
		)
		(pin "2"
		)
		(instances
			(project "polarfire-som"
				(path ""
					(reference "C262")
					(unit 1)
				)
			)
		)
	)
	(symbol
		(lib_id "antmicroCapacitors0402:C_1n_0402")
		(at 20.32 168.91 90)
		(unit 1)
		(exclude_from_sim no)
		(in_bom yes)
		(on_board yes)
		(dnp no)
		(fields_autoplaced yes)
		(property "Reference" "C1"
			(at 22.86 165.0936 90)
			(effects
				(font
					(size 1.27 1.27)
					(thickness 0.15)
				)
				(justify right)
			)
		)
		(property "Value" "C_1n_0402"
			(at 30.48 148.59 0)
			(effects
				(font
					(size 1.27 1.27)
					(thickness 0.15)
				)
				(justify left bottom)
				(hide yes)
			)
		)
		(property "Footprint" "antmicro-footprints:C_0402_1005Metric"
			(at 33.02 148.59 0)
			(effects
				(font
					(size 1.27 1.27)
					(thickness 0.15)
				)
				(justify left bottom)
				(hide yes)
			)
		)
		(property "Datasheet" "https://www.murata.com/products/productdetail?partno=GRM1555C1H102JA01%23"
			(at 35.56 148.59 0)
			(effects
				(font
					(size 1.27 1.27)
					(thickness 0.15)
				)
				(justify left bottom)
				(hide yes)
			)
		)
		(property "Description" "SMD Multilayer Ceramic Capacitor, 1000 pF, 50 V, 0402 [1005 Metric], ± 5%, C0G / NP0, GRM Series"
			(at 20.32 168.91 0)
			(effects
				(font
					(size 1.27 1.27)
				)
				(hide yes)
			)
		)
		(property "MPN" "GRM1555C1H102JA01D"
			(at 38.1 148.59 0)
			(effects
				(font
					(size 1.27 1.27)
					(thickness 0.15)
				)
				(justify left bottom)
				(hide yes)
			)
		)
		(property "Manufacturer" "Murata"
			(at 40.64 148.59 0)
			(effects
				(font
					(size 1.27 1.27)
					(thickness 0.15)
				)
				(justify left bottom)
				(hide yes)
			)
		)
		(property "License" "Apache-2.0"
			(at 43.18 148.59 0)
			(effects
				(font
					(size 1.27 1.27)
					(thickness 0.15)
				)
				(justify left bottom)
				(hide yes)
			)
		)
		(property "Author" "Antmicro"
			(at 45.72 148.59 0)
			(effects
				(font
					(size 1.27 1.27)
					(thickness 0.15)
				)
				(justify left bottom)
				(hide yes)
			)
		)
		(property "Val" "1n"
			(at 22.86 167.6336 90)
			(effects
				(font
					(size 1.27 1.27)
					(thickness 0.15)
				)
				(justify right)
			)
		)
		(property "Voltage" "50V"
			(at 48.26 148.59 0)
			(effects
				(font
					(size 1.27 1.27)
				)
				(justify left bottom)
				(hide yes)
			)
		)
		(property "Dielectric" "C0G"
			(at 50.8 148.59 0)
			(effects
				(font
					(size 1.27 1.27)
				)
				(justify left bottom)
				(hide yes)
			)
		)
		(property "Public" ""
			(at 53.34 148.59 0)
			(effects
				(font
					(size 1.27 1.27)
				)
				(justify left bottom)
				(hide yes)
			)
		)
		(pin "1"
		)
		(pin "2"
		)
		(instances
			(project "polarfire-som"
				(path ""
					(reference "C1")
					(unit 1)
				)
			)
		)
	)
	(symbol
		(lib_id "antmicropower:GND")
		(at 176.53 171.45 0)
		(unit 1)
		(exclude_from_sim no)
		(in_bom yes)
		(on_board yes)
		(dnp no)
		(property "Reference" "#PWR030"
			(at 185.42 173.99 0)
			(effects
				(font
					(size 1.27 1.27)
					(thickness 0.15)
				)
				(justify left bottom)
				(hide yes)
			)
		)
		(property "Value" "GND"
			(at 176.53 175.26 0)
			(effects
				(font
					(size 1.27 1.27)
					(thickness 0.15)
				)
			)
		)
		(property "Footprint" ""
			(at 185.42 179.07 0)
			(effects
				(font
					(size 1.27 1.27)
					(thickness 0.15)
				)
				(justify left bottom)
				(hide yes)
			)
		)
		(property "Datasheet" ""
			(at 185.42 184.15 0)
			(effects
				(font
					(size 1.27 1.27)
					(thickness 0.15)
				)
				(justify left bottom)
				(hide yes)
			)
		)
		(property "Description" ""
			(at 176.53 171.45 0)
			(effects
				(font
					(size 1.27 1.27)
				)
				(hide yes)
			)
		)
		(property "Author" "Antmicro"
			(at 185.42 179.07 0)
			(effects
				(font
					(size 1.27 1.27)
					(thickness 0.15)
				)
				(justify left bottom)
				(hide yes)
			)
		)
		(property "License" "Apache-2.0"
			(at 185.42 181.61 0)
			(effects
				(font
					(size 1.27 1.27)
					(thickness 0.15)
				)
				(justify left bottom)
				(hide yes)
			)
		)
		(pin "1"
		)
		(instances
			(project "polarfire-som"
				(path ""
					(reference "#PWR030")
					(unit 1)
				)
			)
		)
	)
	(symbol
		(lib_id "antmicropower:PWR_FLAG")
		(at 176.53 87.63 0)
		(unit 1)
		(exclude_from_sim no)
		(in_bom yes)
		(on_board yes)
		(dnp no)
		(property "Reference" "#FLG016"
			(at 176.53 85.725 0)
			(effects
				(font
					(size 1.27 1.27)
				)
				(hide yes)
			)
		)
		(property "Value" "PWR_FLAG"
			(at 176.53 83.82 0)
			(effects
				(font
					(size 1.27 1.27)
				)
			)
		)
		(property "Footprint" ""
			(at 176.53 87.63 0)
			(effects
				(font
					(size 1.27 1.27)
				)
				(hide yes)
			)
		)
		(property "Datasheet" ""
			(at 176.53 87.63 0)
			(effects
				(font
					(size 1.27 1.27)
				)
				(hide yes)
			)
		)
		(property "Description" ""
			(at 176.53 87.63 0)
			(effects
				(font
					(size 1.27 1.27)
				)
				(hide yes)
			)
		)
		(pin "1"
		)
		(instances
			(project "polarfire-som"
				(path ""
					(reference "#FLG016")
					(unit 1)
				)
			)
		)
	)
	(symbol
		(lib_id "antmicropower:GND")
		(at 182.88 248.92 0)
		(unit 1)
		(exclude_from_sim no)
		(in_bom yes)
		(on_board yes)
		(dnp no)
		(property "Reference" "#PWR033"
			(at 191.77 251.46 0)
			(effects
				(font
					(size 1.27 1.27)
					(thickness 0.15)
				)
				(justify left bottom)
				(hide yes)
			)
		)
		(property "Value" "GND"
			(at 182.88 252.73 0)
			(effects
				(font
					(size 1.27 1.27)
					(thickness 0.15)
				)
			)
		)
		(property "Footprint" ""
			(at 191.77 256.54 0)
			(effects
				(font
					(size 1.27 1.27)
					(thickness 0.15)
				)
				(justify left bottom)
				(hide yes)
			)
		)
		(property "Datasheet" ""
			(at 191.77 261.62 0)
			(effects
				(font
					(size 1.27 1.27)
					(thickness 0.15)
				)
				(justify left bottom)
				(hide yes)
			)
		)
		(property "Description" ""
			(at 182.88 248.92 0)
			(effects
				(font
					(size 1.27 1.27)
				)
				(hide yes)
			)
		)
		(property "Author" "Antmicro"
			(at 191.77 256.54 0)
			(effects
				(font
					(size 1.27 1.27)
					(thickness 0.15)
				)
				(justify left bottom)
				(hide yes)
			)
		)
		(property "License" "Apache-2.0"
			(at 191.77 259.08 0)
			(effects
				(font
					(size 1.27 1.27)
					(thickness 0.15)
				)
				(justify left bottom)
				(hide yes)
			)
		)
		(pin "1"
		)
		(instances
			(project "polarfire-som"
				(path ""
					(reference "#PWR033")
					(unit 1)
				)
			)
		)
	)
	(symbol
		(lib_id "antmicropower:PWR_FLAG")
		(at 246.38 83.82 0)
		(unit 1)
		(exclude_from_sim no)
		(in_bom yes)
		(on_board yes)
		(dnp no)
		(property "Reference" "#FLG015"
			(at 246.38 81.915 0)
			(effects
				(font
					(size 1.27 1.27)
				)
				(hide yes)
			)
		)
		(property "Value" "PWR_FLAG"
			(at 246.38 80.01 0)
			(effects
				(font
					(size 1.27 1.27)
				)
			)
		)
		(property "Footprint" ""
			(at 246.38 83.82 0)
			(effects
				(font
					(size 1.27 1.27)
				)
				(hide yes)
			)
		)
		(property "Datasheet" ""
			(at 246.38 83.82 0)
			(effects
				(font
					(size 1.27 1.27)
				)
				(hide yes)
			)
		)
		(property "Description" ""
			(at 246.38 83.82 0)
			(effects
				(font
					(size 1.27 1.27)
				)
				(hide yes)
			)
		)
		(pin "1"
		)
		(instances
			(project "polarfire-som"
				(path ""
					(reference "#FLG015")
					(unit 1)
				)
			)
		)
	)
	(symbol
		(lib_id "antmicroCapacitors0402:C_22n_0402")
		(at 135.89 168.91 90)
		(unit 1)
		(exclude_from_sim no)
		(in_bom yes)
		(on_board yes)
		(dnp no)
		(fields_autoplaced yes)
		(property "Reference" "C28"
			(at 138.43 165.0936 90)
			(effects
				(font
					(size 1.27 1.27)
					(thickness 0.15)
				)
				(justify right)
			)
		)
		(property "Value" "C_22n_0402"
			(at 146.05 148.59 0)
			(effects
				(font
					(size 1.27 1.27)
					(thickness 0.15)
				)
				(justify left bottom)
				(hide yes)
			)
		)
		(property "Footprint" "antmicro-footprints:C_0402_1005Metric"
			(at 148.59 148.59 0)
			(effects
				(font
					(size 1.27 1.27)
					(thickness 0.15)
				)
				(justify left bottom)
				(hide yes)
			)
		)
		(property "Datasheet" "https://www.murata.com/products/productdetail?partno=GCM155R71H223MA55%23"
			(at 151.13 148.59 0)
			(effects
				(font
					(size 1.27 1.27)
					(thickness 0.15)
				)
				(justify left bottom)
				(hide yes)
			)
		)
		(property "Description" "SMD Multilayer Ceramic Capacitors, 0.022 µF, 50 V, 20%, 0402 [1005 Metric], X7R"
			(at 135.89 168.91 0)
			(effects
				(font
					(size 1.27 1.27)
				)
				(hide yes)
			)
		)
		(property "MPN" "GCM155R71H223MA55D"
			(at 153.67 148.59 0)
			(effects
				(font
					(size 1.27 1.27)
					(thickness 0.15)
				)
				(justify left bottom)
				(hide yes)
			)
		)
		(property "Manufacturer" "Murata"
			(at 156.21 148.59 0)
			(effects
				(font
					(size 1.27 1.27)
					(thickness 0.15)
				)
				(justify left bottom)
				(hide yes)
			)
		)
		(property "License" "Apache-2.0"
			(at 158.75 148.59 0)
			(effects
				(font
					(size 1.27 1.27)
					(thickness 0.15)
				)
				(justify left bottom)
				(hide yes)
			)
		)
		(property "Author" "Antmicro"
			(at 161.29 148.59 0)
			(effects
				(font
					(size 1.27 1.27)
					(thickness 0.15)
				)
				(justify left bottom)
				(hide yes)
			)
		)
		(property "Val" "22n"
			(at 138.43 167.6336 90)
			(effects
				(font
					(size 1.27 1.27)
					(thickness 0.15)
				)
				(justify right)
			)
		)
		(property "Voltage" ""
			(at 163.83 148.59 0)
			(effects
				(font
					(size 1.27 1.27)
				)
				(justify left bottom)
				(hide yes)
			)
		)
		(property "Dielectric" ""
			(at 166.37 148.59 0)
			(effects
				(font
					(size 1.27 1.27)
				)
				(justify left bottom)
				(hide yes)
			)
		)
		(property "Public" ""
			(at 168.91 148.59 0)
			(effects
				(font
					(size 1.27 1.27)
				)
				(justify left bottom)
				(hide yes)
			)
		)
		(pin "1"
		)
		(pin "2"
		)
		(instances
			(project "polarfire-som"
				(path ""
					(reference "C28")
					(unit 1)
				)
			)
		)
	)
	(symbol
		(lib_id "antmicropower:VDDI")
		(at 152.4 238.76 0)
		(unit 1)
		(exclude_from_sim no)
		(in_bom yes)
		(on_board yes)
		(dnp no)
		(fields_autoplaced yes)
		(property "Reference" "#PWR0326"
			(at 152.4 242.57 0)
			(effects
				(font
					(size 1.27 1.27)
				)
				(hide yes)
			)
		)
		(property "Value" "VDD"
			(at 152.4 234.315 0)
			(effects
				(font
					(size 1.27 1.27)
				)
			)
		)
		(property "Footprint" ""
			(at 152.4 238.76 0)
			(effects
				(font
					(size 1.27 1.27)
				)
				(hide yes)
			)
		)
		(property "Datasheet" ""
			(at 152.4 238.76 0)
			(effects
				(font
					(size 1.27 1.27)
				)
				(hide yes)
			)
		)
		(property "Description" ""
			(at 152.4 238.76 0)
			(effects
				(font
					(size 1.27 1.27)
				)
				(hide yes)
			)
		)
		(pin "1"
		)
		(instances
			(project "polarfire-som"
				(path ""
					(reference "#PWR0326")
					(unit 1)
				)
			)
		)
	)
	(symbol
		(lib_id "antmicropower:GND")
		(at 20.32 248.92 0)
		(unit 1)
		(exclude_from_sim no)
		(in_bom yes)
		(on_board yes)
		(dnp no)
		(property "Reference" "#PWR011"
			(at 29.21 251.46 0)
			(effects
				(font
					(size 1.27 1.27)
					(thickness 0.15)
				)
				(justify left bottom)
				(hide yes)
			)
		)
		(property "Value" "GND"
			(at 20.32 252.73 0)
			(effects
				(font
					(size 1.27 1.27)
					(thickness 0.15)
				)
			)
		)
		(property "Footprint" ""
			(at 29.21 256.54 0)
			(effects
				(font
					(size 1.27 1.27)
					(thickness 0.15)
				)
				(justify left bottom)
				(hide yes)
			)
		)
		(property "Datasheet" ""
			(at 29.21 261.62 0)
			(effects
				(font
					(size 1.27 1.27)
					(thickness 0.15)
				)
				(justify left bottom)
				(hide yes)
			)
		)
		(property "Description" ""
			(at 20.32 248.92 0)
			(effects
				(font
					(size 1.27 1.27)
				)
				(hide yes)
			)
		)
		(property "Author" "Antmicro"
			(at 29.21 256.54 0)
			(effects
				(font
					(size 1.27 1.27)
					(thickness 0.15)
				)
				(justify left bottom)
				(hide yes)
			)
		)
		(property "License" "Apache-2.0"
			(at 29.21 259.08 0)
			(effects
				(font
					(size 1.27 1.27)
					(thickness 0.15)
				)
				(justify left bottom)
				(hide yes)
			)
		)
		(pin "1"
		)
		(instances
			(project "polarfire-som"
				(path ""
					(reference "#PWR011")
					(unit 1)
				)
			)
		)
	)
	(symbol
		(lib_id "antmicropower:GND")
		(at 132.08 223.52 0)
		(unit 1)
		(exclude_from_sim no)
		(in_bom yes)
		(on_board yes)
		(dnp no)
		(property "Reference" "#PWR025"
			(at 140.97 226.06 0)
			(effects
				(font
					(size 1.27 1.27)
					(thickness 0.15)
				)
				(justify left bottom)
				(hide yes)
			)
		)
		(property "Value" "GND"
			(at 132.08 227.33 0)
			(effects
				(font
					(size 1.27 1.27)
					(thickness 0.15)
				)
			)
		)
		(property "Footprint" ""
			(at 140.97 231.14 0)
			(effects
				(font
					(size 1.27 1.27)
					(thickness 0.15)
				)
				(justify left bottom)
				(hide yes)
			)
		)
		(property "Datasheet" ""
			(at 140.97 236.22 0)
			(effects
				(font
					(size 1.27 1.27)
					(thickness 0.15)
				)
				(justify left bottom)
				(hide yes)
			)
		)
		(property "Description" ""
			(at 132.08 223.52 0)
			(effects
				(font
					(size 1.27 1.27)
				)
				(hide yes)
			)
		)
		(property "Author" "Antmicro"
			(at 140.97 231.14 0)
			(effects
				(font
					(size 1.27 1.27)
					(thickness 0.15)
				)
				(justify left bottom)
				(hide yes)
			)
		)
		(property "License" "Apache-2.0"
			(at 140.97 233.68 0)
			(effects
				(font
					(size 1.27 1.27)
					(thickness 0.15)
				)
				(justify left bottom)
				(hide yes)
			)
		)
		(pin "1"
		)
		(instances
			(project "polarfire-som"
				(path ""
					(reference "#PWR025")
					(unit 1)
				)
			)
		)
	)
	(symbol
		(lib_id "antmicroCapacitors0402:C_1n_0402")
		(at 101.6 220.98 90)
		(unit 1)
		(exclude_from_sim no)
		(in_bom yes)
		(on_board yes)
		(dnp no)
		(fields_autoplaced yes)
		(property "Reference" "C30"
			(at 104.14 217.1636 90)
			(effects
				(font
					(size 1.27 1.27)
					(thickness 0.15)
				)
				(justify right)
			)
		)
		(property "Value" "C_1n_0402"
			(at 111.76 200.66 0)
			(effects
				(font
					(size 1.27 1.27)
					(thickness 0.15)
				)
				(justify left bottom)
				(hide yes)
			)
		)
		(property "Footprint" "antmicro-footprints:C_0402_1005Metric"
			(at 114.3 200.66 0)
			(effects
				(font
					(size 1.27 1.27)
					(thickness 0.15)
				)
				(justify left bottom)
				(hide yes)
			)
		)
		(property "Datasheet" "https://www.murata.com/products/productdetail?partno=GRM1555C1H102JA01%23"
			(at 116.84 200.66 0)
			(effects
				(font
					(size 1.27 1.27)
					(thickness 0.15)
				)
				(justify left bottom)
				(hide yes)
			)
		)
		(property "Description" "SMD Multilayer Ceramic Capacitor, 1000 pF, 50 V, 0402 [1005 Metric], ± 5%, C0G / NP0, GRM Series"
			(at 101.6 220.98 0)
			(effects
				(font
					(size 1.27 1.27)
				)
				(hide yes)
			)
		)
		(property "MPN" "GRM1555C1H102JA01D"
			(at 119.38 200.66 0)
			(effects
				(font
					(size 1.27 1.27)
					(thickness 0.15)
				)
				(justify left bottom)
				(hide yes)
			)
		)
		(property "Manufacturer" "Murata"
			(at 121.92 200.66 0)
			(effects
				(font
					(size 1.27 1.27)
					(thickness 0.15)
				)
				(justify left bottom)
				(hide yes)
			)
		)
		(property "License" "Apache-2.0"
			(at 124.46 200.66 0)
			(effects
				(font
					(size 1.27 1.27)
					(thickness 0.15)
				)
				(justify left bottom)
				(hide yes)
			)
		)
		(property "Author" "Antmicro"
			(at 127 200.66 0)
			(effects
				(font
					(size 1.27 1.27)
					(thickness 0.15)
				)
				(justify left bottom)
				(hide yes)
			)
		)
		(property "Val" "1n"
			(at 104.14 219.7036 90)
			(effects
				(font
					(size 1.27 1.27)
					(thickness 0.15)
				)
				(justify right)
			)
		)
		(property "Voltage" "50V"
			(at 129.54 200.66 0)
			(effects
				(font
					(size 1.27 1.27)
				)
				(justify left bottom)
				(hide yes)
			)
		)
		(property "Dielectric" "C0G"
			(at 132.08 200.66 0)
			(effects
				(font
					(size 1.27 1.27)
				)
				(justify left bottom)
				(hide yes)
			)
		)
		(property "Public" ""
			(at 134.62 200.66 0)
			(effects
				(font
					(size 1.27 1.27)
				)
				(justify left bottom)
				(hide yes)
			)
		)
		(pin "1"
		)
		(pin "2"
		)
		(instances
			(project "polarfire-som"
				(path ""
					(reference "C30")
					(unit 1)
				)
			)
		)
	)
	(symbol
		(lib_id "antmicroCapacitors0402:C_100n_0402")
		(at 172.72 246.38 90)
		(unit 1)
		(exclude_from_sim no)
		(in_bom yes)
		(on_board yes)
		(dnp no)
		(fields_autoplaced yes)
		(property "Reference" "C62"
			(at 175.26 242.5636 90)
			(effects
				(font
					(size 1.27 1.27)
					(thickness 0.15)
				)
				(justify right)
			)
		)
		(property "Value" "C_100n_0402"
			(at 182.88 226.06 0)
			(effects
				(font
					(size 1.27 1.27)
					(thickness 0.15)
				)
				(justify left bottom)
				(hide yes)
			)
		)
		(property "Footprint" "antmicro-footprints:C_0402_1005Metric"
			(at 185.42 226.06 0)
			(effects
				(font
					(size 1.27 1.27)
					(thickness 0.15)
				)
				(justify left bottom)
				(hide yes)
			)
		)
		(property "Datasheet" "https://www.murata.com/products/productdetail?partno=GRM155R61H104KE14%23"
			(at 187.96 226.06 0)
			(effects
				(font
					(size 1.27 1.27)
					(thickness 0.15)
				)
				(justify left bottom)
				(hide yes)
			)
		)
		(property "Description" "SMD Multilayer Ceramic Capacitor, 0.1 µF, 50 V, 0402 [1005 Metric], ± 10%, X5R, GRM Series"
			(at 172.72 246.38 0)
			(effects
				(font
					(size 1.27 1.27)
				)
				(hide yes)
			)
		)
		(property "MPN" "GRM155R61H104KE14D"
			(at 190.5 226.06 0)
			(effects
				(font
					(size 1.27 1.27)
					(thickness 0.15)
				)
				(justify left bottom)
				(hide yes)
			)
		)
		(property "Manufacturer" "Murata"
			(at 193.04 226.06 0)
			(effects
				(font
					(size 1.27 1.27)
					(thickness 0.15)
				)
				(justify left bottom)
				(hide yes)
			)
		)
		(property "License" "Apache-2.0"
			(at 195.58 226.06 0)
			(effects
				(font
					(size 1.27 1.27)
					(thickness 0.15)
				)
				(justify left bottom)
				(hide yes)
			)
		)
		(property "Author" "Antmicro"
			(at 198.12 226.06 0)
			(effects
				(font
					(size 1.27 1.27)
					(thickness 0.15)
				)
				(justify left bottom)
				(hide yes)
			)
		)
		(property "Val" "100n"
			(at 175.26 245.1036 90)
			(effects
				(font
					(size 1.27 1.27)
					(thickness 0.15)
				)
				(justify right)
			)
		)
		(property "Voltage" "50V"
			(at 200.66 226.06 0)
			(effects
				(font
					(size 1.27 1.27)
				)
				(justify left bottom)
				(hide yes)
			)
		)
		(property "Dielectric" "X5R"
			(at 203.2 226.06 0)
			(effects
				(font
					(size 1.27 1.27)
				)
				(justify left bottom)
				(hide yes)
			)
		)
		(property "Public" ""
			(at 205.74 226.06 0)
			(effects
				(font
					(size 1.27 1.27)
				)
				(justify left bottom)
				(hide yes)
			)
		)
		(pin "1"
		)
		(pin "2"
		)
		(instances
			(project "polarfire-som"
				(path ""
					(reference "C62")
					(unit 1)
				)
			)
		)
	)
	(symbol
		(lib_id "antmicroCapacitors0402:C_10u_0402")
		(at 34.29 196.85 90)
		(unit 1)
		(exclude_from_sim no)
		(in_bom yes)
		(on_board yes)
		(dnp no)
		(fields_autoplaced yes)
		(property "Reference" "C10"
			(at 37.465 193.0335 90)
			(effects
				(font
					(size 1.27 1.27)
					(thickness 0.15)
				)
				(justify right)
			)
		)
		(property "Value" "C_10u_0402"
			(at 44.45 176.53 0)
			(effects
				(font
					(size 1.27 1.27)
					(thickness 0.15)
				)
				(justify left bottom)
				(hide yes)
			)
		)
		(property "Footprint" "antmicro-footprints:C_0402_1005Metric"
			(at 46.99 176.53 0)
			(effects
				(font
					(size 1.27 1.27)
					(thickness 0.15)
				)
				(justify left bottom)
				(hide yes)
			)
		)
		(property "Datasheet" "https://www.yageo.com/en/Chart/Download/pdf/CC0402MRX5R5BB106"
			(at 49.53 176.53 0)
			(effects
				(font
					(size 1.27 1.27)
					(thickness 0.15)
				)
				(justify left bottom)
				(hide yes)
			)
		)
		(property "Description" "SMD Multilayer Ceramic Capacitor, 10 µF, 6.3 V, 0402 [1005 Metric], ± 20%, X5R, CC Series"
			(at 34.29 196.85 0)
			(effects
				(font
					(size 1.27 1.27)
				)
				(hide yes)
			)
		)
		(property "MPN" "CC0402MRX5R5BB106"
			(at 52.07 176.53 0)
			(effects
				(font
					(size 1.27 1.27)
					(thickness 0.15)
				)
				(justify left bottom)
				(hide yes)
			)
		)
		(property "Manufacturer" "YAGEO"
			(at 54.61 176.53 0)
			(effects
				(font
					(size 1.27 1.27)
					(thickness 0.15)
				)
				(justify left bottom)
				(hide yes)
			)
		)
		(property "License" "Apache-2.0"
			(at 57.15 176.53 0)
			(effects
				(font
					(size 1.27 1.27)
					(thickness 0.15)
				)
				(justify left bottom)
				(hide yes)
			)
		)
		(property "Author" "Antmicro"
			(at 59.69 176.53 0)
			(effects
				(font
					(size 1.27 1.27)
					(thickness 0.15)
				)
				(justify left bottom)
				(hide yes)
			)
		)
		(property "Val" "10u"
			(at 37.465 195.5735 90)
			(effects
				(font
					(size 1.27 1.27)
					(thickness 0.15)
				)
				(justify right)
			)
		)
		(property "Voltage" ""
			(at 62.23 176.53 0)
			(effects
				(font
					(size 1.27 1.27)
				)
				(justify left bottom)
				(hide yes)
			)
		)
		(property "Dielectric" ""
			(at 64.77 176.53 0)
			(effects
				(font
					(size 1.27 1.27)
				)
				(justify left bottom)
				(hide yes)
			)
		)
		(property "Public" ""
			(at 67.31 176.53 0)
			(effects
				(font
					(size 1.27 1.27)
				)
				(justify left bottom)
				(hide yes)
			)
		)
		(pin "1"
		)
		(pin "2"
		)
		(instances
			(project "polarfire-som"
				(path ""
					(reference "C10")
					(unit 1)
				)
			)
		)
	)
	(symbol
		(lib_id "antmicropower:VDDAUX")
		(at 166.37 269.24 0)
		(unit 1)
		(exclude_from_sim no)
		(in_bom yes)
		(on_board yes)
		(dnp no)
		(property "Reference" "#PWR0329"
			(at 166.37 273.05 0)
			(effects
				(font
					(size 1.27 1.27)
				)
				(hide yes)
			)
		)
		(property "Value" "VDDAUX"
			(at 166.37 265.43 0)
			(effects
				(font
					(size 1.27 1.27)
				)
			)
		)
		(property "Footprint" ""
			(at 166.37 269.24 0)
			(effects
				(font
					(size 1.27 1.27)
				)
				(hide yes)
			)
		)
		(property "Datasheet" ""
			(at 166.37 269.24 0)
			(effects
				(font
					(size 1.27 1.27)
				)
				(hide yes)
			)
		)
		(property "Description" ""
			(at 166.37 269.24 0)
			(effects
				(font
					(size 1.27 1.27)
				)
				(hide yes)
			)
		)
		(pin "1"
		)
		(instances
			(project "polarfire-som"
				(path ""
					(reference "#PWR0329")
					(unit 1)
				)
			)
		)
	)
	(symbol
		(lib_id "antmicroCapacitors0402:C_4n7_0402")
		(at 162.56 246.38 90)
		(unit 1)
		(exclude_from_sim no)
		(in_bom yes)
		(on_board yes)
		(dnp no)
		(fields_autoplaced yes)
		(property "Reference" "C57"
			(at 165.1 242.5636 90)
			(effects
				(font
					(size 1.27 1.27)
					(thickness 0.15)
				)
				(justify right)
			)
		)
		(property "Value" "C_4n7_0402"
			(at 172.72 226.06 0)
			(effects
				(font
					(size 1.27 1.27)
					(thickness 0.15)
				)
				(justify left bottom)
				(hide yes)
			)
		)
		(property "Footprint" "antmicro-footprints:C_0402_1005Metric"
			(at 175.26 226.06 0)
			(effects
				(font
					(size 1.27 1.27)
					(thickness 0.15)
				)
				(justify left bottom)
				(hide yes)
			)
		)
		(property "Datasheet" "https://product.tdk.com/en/search/capacitor/ceramic/mlcc/info?part_no=CGA2B3X7S2A472K050BB"
			(at 177.8 226.06 0)
			(effects
				(font
					(size 1.27 1.27)
					(thickness 0.15)
				)
				(justify left bottom)
				(hide yes)
			)
		)
		(property "Description" "SMD Multilayer Ceramic Capacitor, 4700 pF, 100 V, 0402 [1005 Metric], ± 10%, X7S, CGA"
			(at 162.56 246.38 0)
			(effects
				(font
					(size 1.27 1.27)
				)
				(hide yes)
			)
		)
		(property "MPN" "CGA2B3X7S2A472K050BB"
			(at 180.34 226.06 0)
			(effects
				(font
					(size 1.27 1.27)
					(thickness 0.15)
				)
				(justify left bottom)
				(hide yes)
			)
		)
		(property "Manufacturer" "TDK"
			(at 182.88 226.06 0)
			(effects
				(font
					(size 1.27 1.27)
					(thickness 0.15)
				)
				(justify left bottom)
				(hide yes)
			)
		)
		(property "License" "Apache-2.0"
			(at 185.42 226.06 0)
			(effects
				(font
					(size 1.27 1.27)
					(thickness 0.15)
				)
				(justify left bottom)
				(hide yes)
			)
		)
		(property "Author" "Antmicro"
			(at 187.96 226.06 0)
			(effects
				(font
					(size 1.27 1.27)
					(thickness 0.15)
				)
				(justify left bottom)
				(hide yes)
			)
		)
		(property "Val" "4n7"
			(at 165.1 245.1036 90)
			(effects
				(font
					(size 1.27 1.27)
					(thickness 0.15)
				)
				(justify right)
			)
		)
		(property "Voltage" "25V"
			(at 190.5 226.06 0)
			(effects
				(font
					(size 1.27 1.27)
				)
				(justify left bottom)
				(hide yes)
			)
		)
		(property "Dielectric" "X7R"
			(at 193.04 226.06 0)
			(effects
				(font
					(size 1.27 1.27)
				)
				(justify left bottom)
				(hide yes)
			)
		)
		(property "Public" ""
			(at 195.58 226.06 0)
			(effects
				(font
					(size 1.27 1.27)
				)
				(justify left bottom)
				(hide yes)
			)
		)
		(pin "1"
		)
		(pin "2"
		)
		(instances
			(project "polarfire-som"
				(path ""
					(reference "C57")
					(unit 1)
				)
			)
		)
	)
	(symbol
		(lib_id "antmicroCapacitors0402:C_10n_0402")
		(at 95.25 168.91 90)
		(unit 1)
		(exclude_from_sim no)
		(in_bom yes)
		(on_board yes)
		(dnp no)
		(fields_autoplaced yes)
		(property "Reference" "C32"
			(at 97.79 165.0936 90)
			(effects
				(font
					(size 1.27 1.27)
					(thickness 0.15)
				)
				(justify right)
			)
		)
		(property "Value" "C_10n_0402"
			(at 105.41 148.59 0)
			(effects
				(font
					(size 1.27 1.27)
					(thickness 0.15)
				)
				(justify left bottom)
				(hide yes)
			)
		)
		(property "Footprint" "antmicro-footprints:C_0402_1005Metric"
			(at 107.95 148.59 0)
			(effects
				(font
					(size 1.27 1.27)
					(thickness 0.15)
				)
				(justify left bottom)
				(hide yes)
			)
		)
		(property "Datasheet" "https://www.murata.com/products/productdetail?partno=GRM155R71H103KA88%23"
			(at 110.49 148.59 0)
			(effects
				(font
					(size 1.27 1.27)
					(thickness 0.15)
				)
				(justify left bottom)
				(hide yes)
			)
		)
		(property "Description" "SMD Multilayer Ceramic Capacitor, 10000 pF, 50 V, 0402 [1005 Metric], ± 10%, X7R, GRM Series"
			(at 95.25 168.91 0)
			(effects
				(font
					(size 1.27 1.27)
				)
				(hide yes)
			)
		)
		(property "MPN" "GRM155R71H103KA88D"
			(at 113.03 148.59 0)
			(effects
				(font
					(size 1.27 1.27)
					(thickness 0.15)
				)
				(justify left bottom)
				(hide yes)
			)
		)
		(property "Manufacturer" "Murata"
			(at 115.57 148.59 0)
			(effects
				(font
					(size 1.27 1.27)
					(thickness 0.15)
				)
				(justify left bottom)
				(hide yes)
			)
		)
		(property "License" "Apache-2.0"
			(at 118.11 148.59 0)
			(effects
				(font
					(size 1.27 1.27)
					(thickness 0.15)
				)
				(justify left bottom)
				(hide yes)
			)
		)
		(property "Author" "Antmicro"
			(at 120.65 148.59 0)
			(effects
				(font
					(size 1.27 1.27)
					(thickness 0.15)
				)
				(justify left bottom)
				(hide yes)
			)
		)
		(property "Val" "10n"
			(at 97.79 167.6336 90)
			(effects
				(font
					(size 1.27 1.27)
					(thickness 0.15)
				)
				(justify right)
			)
		)
		(property "Voltage" "50V"
			(at 123.19 148.59 0)
			(effects
				(font
					(size 1.27 1.27)
				)
				(justify left bottom)
				(hide yes)
			)
		)
		(property "Dielectric" "X7R"
			(at 125.73 148.59 0)
			(effects
				(font
					(size 1.27 1.27)
				)
				(justify left bottom)
				(hide yes)
			)
		)
		(property "Public" ""
			(at 128.27 148.59 0)
			(effects
				(font
					(size 1.27 1.27)
				)
				(justify left bottom)
				(hide yes)
			)
		)
		(pin "1"
		)
		(pin "2"
		)
		(instances
			(project "polarfire-som"
				(path ""
					(reference "C32")
					(unit 1)
				)
			)
		)
	)
	(symbol
		(lib_id "antmicropower:GND")
		(at 106.68 198.12 0)
		(unit 1)
		(exclude_from_sim no)
		(in_bom yes)
		(on_board yes)
		(dnp no)
		(property "Reference" "#PWR023"
			(at 115.57 200.66 0)
			(effects
				(font
					(size 1.27 1.27)
					(thickness 0.15)
				)
				(justify left bottom)
				(hide yes)
			)
		)
		(property "Value" "GND"
			(at 106.68 201.93 0)
			(effects
				(font
					(size 1.27 1.27)
					(thickness 0.15)
				)
			)
		)
		(property "Footprint" ""
			(at 115.57 205.74 0)
			(effects
				(font
					(size 1.27 1.27)
					(thickness 0.15)
				)
				(justify left bottom)
				(hide yes)
			)
		)
		(property "Datasheet" ""
			(at 115.57 210.82 0)
			(effects
				(font
					(size 1.27 1.27)
					(thickness 0.15)
				)
				(justify left bottom)
				(hide yes)
			)
		)
		(property "Description" ""
			(at 106.68 198.12 0)
			(effects
				(font
					(size 1.27 1.27)
				)
				(hide yes)
			)
		)
		(property "Author" "Antmicro"
			(at 115.57 205.74 0)
			(effects
				(font
					(size 1.27 1.27)
					(thickness 0.15)
				)
				(justify left bottom)
				(hide yes)
			)
		)
		(property "License" "Apache-2.0"
			(at 115.57 208.28 0)
			(effects
				(font
					(size 1.27 1.27)
					(thickness 0.15)
				)
				(justify left bottom)
				(hide yes)
			)
		)
		(pin "1"
		)
		(instances
			(project "polarfire-som"
				(path ""
					(reference "#PWR023")
					(unit 1)
				)
			)
		)
	)
	(symbol
		(lib_id "antmicroCapacitors0402:C_10n_0402")
		(at 129.54 195.58 90)
		(unit 1)
		(exclude_from_sim no)
		(in_bom yes)
		(on_board yes)
		(dnp no)
		(fields_autoplaced yes)
		(property "Reference" "C42"
			(at 132.08 191.7636 90)
			(effects
				(font
					(size 1.27 1.27)
					(thickness 0.15)
				)
				(justify right)
			)
		)
		(property "Value" "C_10n_0402"
			(at 139.7 175.26 0)
			(effects
				(font
					(size 1.27 1.27)
					(thickness 0.15)
				)
				(justify left bottom)
				(hide yes)
			)
		)
		(property "Footprint" "antmicro-footprints:C_0402_1005Metric"
			(at 142.24 175.26 0)
			(effects
				(font
					(size 1.27 1.27)
					(thickness 0.15)
				)
				(justify left bottom)
				(hide yes)
			)
		)
		(property "Datasheet" "https://www.murata.com/products/productdetail?partno=GRM155R71H103KA88%23"
			(at 144.78 175.26 0)
			(effects
				(font
					(size 1.27 1.27)
					(thickness 0.15)
				)
				(justify left bottom)
				(hide yes)
			)
		)
		(property "Description" "SMD Multilayer Ceramic Capacitor, 10000 pF, 50 V, 0402 [1005 Metric], ± 10%, X7R, GRM Series"
			(at 129.54 195.58 0)
			(effects
				(font
					(size 1.27 1.27)
				)
				(hide yes)
			)
		)
		(property "MPN" "GRM155R71H103KA88D"
			(at 147.32 175.26 0)
			(effects
				(font
					(size 1.27 1.27)
					(thickness 0.15)
				)
				(justify left bottom)
				(hide yes)
			)
		)
		(property "Manufacturer" "Murata"
			(at 149.86 175.26 0)
			(effects
				(font
					(size 1.27 1.27)
					(thickness 0.15)
				)
				(justify left bottom)
				(hide yes)
			)
		)
		(property "License" "Apache-2.0"
			(at 152.4 175.26 0)
			(effects
				(font
					(size 1.27 1.27)
					(thickness 0.15)
				)
				(justify left bottom)
				(hide yes)
			)
		)
		(property "Author" "Antmicro"
			(at 154.94 175.26 0)
			(effects
				(font
					(size 1.27 1.27)
					(thickness 0.15)
				)
				(justify left bottom)
				(hide yes)
			)
		)
		(property "Val" "10n"
			(at 132.08 194.3036 90)
			(effects
				(font
					(size 1.27 1.27)
					(thickness 0.15)
				)
				(justify right)
			)
		)
		(property "Voltage" "50V"
			(at 157.48 175.26 0)
			(effects
				(font
					(size 1.27 1.27)
				)
				(justify left bottom)
				(hide yes)
			)
		)
		(property "Dielectric" "X7R"
			(at 160.02 175.26 0)
			(effects
				(font
					(size 1.27 1.27)
				)
				(justify left bottom)
				(hide yes)
			)
		)
		(property "Public" ""
			(at 162.56 175.26 0)
			(effects
				(font
					(size 1.27 1.27)
				)
				(justify left bottom)
				(hide yes)
			)
		)
		(pin "1"
		)
		(pin "2"
		)
		(instances
			(project "polarfire-som"
				(path ""
					(reference "C42")
					(unit 1)
				)
			)
		)
	)
	(symbol
		(lib_id "antmicroResistors0402:R_10k_0402")
		(at 242.57 99.06 90)
		(unit 1)
		(exclude_from_sim no)
		(in_bom yes)
		(on_board yes)
		(dnp no)
		(fields_autoplaced yes)
		(property "Reference" "R14"
			(at 244.475 95.2499 90)
			(effects
				(font
					(size 1.27 1.27)
					(thickness 0.15)
				)
				(justify right)
			)
		)
		(property "Value" "R_10k_0402"
			(at 255.27 78.74 0)
			(effects
				(font
					(size 1.27 1.27)
					(thickness 0.15)
				)
				(justify left bottom)
				(hide yes)
			)
		)
		(property "Footprint" "antmicro-footprints:R_0402_1005Metric"
			(at 257.81 78.74 0)
			(effects
				(font
					(size 1.27 1.27)
					(thickness 0.15)
				)
				(justify left bottom)
				(hide yes)
			)
		)
		(property "Datasheet" "https://www.bourns.com/docs/product-datasheets/cr.pdf"
			(at 260.35 78.74 0)
			(effects
				(font
					(size 1.27 1.27)
					(thickness 0.15)
				)
				(justify left bottom)
				(hide yes)
			)
		)
		(property "Description" "SMD Chip Resistor, 10 kohm, ± 1%, 62.5 mW, 0402 [1005 Metric], Thick Film, General Purpose"
			(at 242.57 99.06 0)
			(effects
				(font
					(size 1.27 1.27)
				)
				(hide yes)
			)
		)
		(property "MPN" "CR0402-FX-1002GLF"
			(at 262.89 78.74 0)
			(effects
				(font
					(size 1.27 1.27)
					(thickness 0.15)
				)
				(justify left bottom)
				(hide yes)
			)
		)
		(property "Manufacturer" "Bourns"
			(at 265.43 78.74 0)
			(effects
				(font
					(size 1.27 1.27)
					(thickness 0.15)
				)
				(justify left bottom)
				(hide yes)
			)
		)
		(property "License" "Apache-2.0"
			(at 267.97 78.74 0)
			(effects
				(font
					(size 1.27 1.27)
					(thickness 0.15)
				)
				(justify left bottom)
				(hide yes)
			)
		)
		(property "Author" "Antmicro"
			(at 270.51 78.74 0)
			(effects
				(font
					(size 1.27 1.27)
					(thickness 0.15)
				)
				(justify left bottom)
				(hide yes)
			)
		)
		(property "Val" "10k"
			(at 244.475 97.7899 90)
			(effects
				(font
					(size 1.27 1.27)
					(thickness 0.15)
				)
				(justify right)
			)
		)
		(property "Tolerance" "1%"
			(at 252.73 78.74 0)
			(effects
				(font
					(size 1.27 1.27)
				)
				(justify left bottom)
				(hide yes)
			)
		)
		(property "Public" ""
			(at 273.05 78.74 0)
			(effects
				(font
					(size 1.27 1.27)
				)
				(justify left bottom)
				(hide yes)
			)
		)
		(pin "1"
		)
		(pin "2"
		)
		(instances
			(project "polarfire-som"
				(path ""
					(reference "R14")
					(unit 1)
				)
			)
		)
	)
	(symbol
		(lib_id "antmicropower:+2V5")
		(at 91.44 213.36 0)
		(unit 1)
		(exclude_from_sim no)
		(in_bom yes)
		(on_board yes)
		(dnp no)
		(property "Reference" "#PWR021"
			(at 91.44 217.17 0)
			(effects
				(font
					(size 1.27 1.27)
				)
				(hide yes)
			)
		)
		(property "Value" "+2V5"
			(at 91.44 209.55 0)
			(effects
				(font
					(size 1.27 1.27)
				)
			)
		)
		(property "Footprint" ""
			(at 91.44 213.36 0)
			(effects
				(font
					(size 1.27 1.27)
				)
				(hide yes)
			)
		)
		(property "Datasheet" ""
			(at 91.44 213.36 0)
			(effects
				(font
					(size 1.27 1.27)
				)
				(hide yes)
			)
		)
		(property "Description" ""
			(at 91.44 213.36 0)
			(effects
				(font
					(size 1.27 1.27)
				)
				(hide yes)
			)
		)
		(pin "1"
		)
		(instances
			(project "polarfire-som"
				(path ""
					(reference "#PWR021")
					(unit 1)
				)
			)
		)
	)
	(symbol
		(lib_id "antmicroCapacitors0402:C_100n_0402")
		(at 96.52 195.58 90)
		(unit 1)
		(exclude_from_sim no)
		(in_bom yes)
		(on_board yes)
		(dnp no)
		(fields_autoplaced yes)
		(property "Reference" "C33"
			(at 99.06 191.7636 90)
			(effects
				(font
					(size 1.27 1.27)
					(thickness 0.15)
				)
				(justify right)
			)
		)
		(property "Value" "C_100n_0402"
			(at 106.68 175.26 0)
			(effects
				(font
					(size 1.27 1.27)
					(thickness 0.15)
				)
				(justify left bottom)
				(hide yes)
			)
		)
		(property "Footprint" "antmicro-footprints:C_0402_1005Metric"
			(at 109.22 175.26 0)
			(effects
				(font
					(size 1.27 1.27)
					(thickness 0.15)
				)
				(justify left bottom)
				(hide yes)
			)
		)
		(property "Datasheet" "https://www.murata.com/products/productdetail?partno=GRM155R61H104KE14%23"
			(at 111.76 175.26 0)
			(effects
				(font
					(size 1.27 1.27)
					(thickness 0.15)
				)
				(justify left bottom)
				(hide yes)
			)
		)
		(property "Description" "SMD Multilayer Ceramic Capacitor, 0.1 µF, 50 V, 0402 [1005 Metric], ± 10%, X5R, GRM Series"
			(at 96.52 195.58 0)
			(effects
				(font
					(size 1.27 1.27)
				)
				(hide yes)
			)
		)
		(property "MPN" "GRM155R61H104KE14D"
			(at 114.3 175.26 0)
			(effects
				(font
					(size 1.27 1.27)
					(thickness 0.15)
				)
				(justify left bottom)
				(hide yes)
			)
		)
		(property "Manufacturer" "Murata"
			(at 116.84 175.26 0)
			(effects
				(font
					(size 1.27 1.27)
					(thickness 0.15)
				)
				(justify left bottom)
				(hide yes)
			)
		)
		(property "License" "Apache-2.0"
			(at 119.38 175.26 0)
			(effects
				(font
					(size 1.27 1.27)
					(thickness 0.15)
				)
				(justify left bottom)
				(hide yes)
			)
		)
		(property "Author" "Antmicro"
			(at 121.92 175.26 0)
			(effects
				(font
					(size 1.27 1.27)
					(thickness 0.15)
				)
				(justify left bottom)
				(hide yes)
			)
		)
		(property "Val" "100n"
			(at 99.06 194.3036 90)
			(effects
				(font
					(size 1.27 1.27)
					(thickness 0.15)
				)
				(justify right)
			)
		)
		(property "Voltage" "50V"
			(at 124.46 175.26 0)
			(effects
				(font
					(size 1.27 1.27)
				)
				(justify left bottom)
				(hide yes)
			)
		)
		(property "Dielectric" "X5R"
			(at 127 175.26 0)
			(effects
				(font
					(size 1.27 1.27)
				)
				(justify left bottom)
				(hide yes)
			)
		)
		(property "Public" ""
			(at 129.54 175.26 0)
			(effects
				(font
					(size 1.27 1.27)
				)
				(justify left bottom)
				(hide yes)
			)
		)
		(pin "1"
		)
		(pin "2"
		)
		(instances
			(project "polarfire-som"
				(path ""
					(reference "C33")
					(unit 1)
				)
			)
		)
	)
	(symbol
		(lib_id "antmicropower:+2V5")
		(at 45.72 238.76 0)
		(unit 1)
		(exclude_from_sim no)
		(in_bom yes)
		(on_board yes)
		(dnp no)
		(property "Reference" "#PWR014"
			(at 45.72 242.57 0)
			(effects
				(font
					(size 1.27 1.27)
				)
				(hide yes)
			)
		)
		(property "Value" "+2V5"
			(at 45.72 234.95 0)
			(effects
				(font
					(size 1.27 1.27)
				)
			)
		)
		(property "Footprint" ""
			(at 45.72 238.76 0)
			(effects
				(font
					(size 1.27 1.27)
				)
				(hide yes)
			)
		)
		(property "Datasheet" ""
			(at 45.72 238.76 0)
			(effects
				(font
					(size 1.27 1.27)
				)
				(hide yes)
			)
		)
		(property "Description" ""
			(at 45.72 238.76 0)
			(effects
				(font
					(size 1.27 1.27)
				)
				(hide yes)
			)
		)
		(pin "1"
		)
		(instances
			(project "polarfire-som"
				(path ""
					(reference "#PWR014")
					(unit 1)
				)
			)
		)
	)
	(symbol
		(lib_id "antmicropower:PWR_FLAG")
		(at 71.12 161.29 0)
		(unit 1)
		(exclude_from_sim no)
		(in_bom yes)
		(on_board yes)
		(dnp no)
		(property "Reference" "#FLG09"
			(at 71.12 159.385 0)
			(effects
				(font
					(size 1.27 1.27)
				)
				(hide yes)
			)
		)
		(property "Value" "PWR_FLAG"
			(at 71.12 157.226 0)
			(effects
				(font
					(size 1.27 1.27)
				)
			)
		)
		(property "Footprint" ""
			(at 71.12 161.29 0)
			(effects
				(font
					(size 1.27 1.27)
				)
				(hide yes)
			)
		)
		(property "Datasheet" ""
			(at 71.12 161.29 0)
			(effects
				(font
					(size 1.27 1.27)
				)
				(hide yes)
			)
		)
		(property "Description" ""
			(at 71.12 161.29 0)
			(effects
				(font
					(size 1.27 1.27)
				)
				(hide yes)
			)
		)
		(pin "1"
		)
		(instances
			(project "polarfire-som"
				(path ""
					(reference "#FLG09")
					(unit 1)
				)
			)
		)
	)
	(symbol
		(lib_id "antmicroCapacitorspol:C_Pol_330u_6.3V_KEMET-T520-B")
		(at 182.88 190.5 270)
		(unit 1)
		(exclude_from_sim no)
		(in_bom yes)
		(on_board yes)
		(dnp no)
		(property "Reference" "C65"
			(at 185.42 191.77 90)
			(effects
				(font
					(size 1.27 1.27)
					(thickness 0.15)
				)
				(justify left)
			)
		)
		(property "Value" "C_Pol_330u_6.3V_KEMET-T520-B"
			(at 180.34 204.47 0)
			(effects
				(font
					(size 1.27 1.27)
					(thickness 0.15)
				)
				(justify left bottom)
				(hide yes)
			)
		)
		(property "Footprint" "antmicro-footprints:C_Pol_EIA-B"
			(at 175.26 204.47 0)
			(effects
				(font
					(size 1.27 1.27)
					(thickness 0.15)
				)
				(justify left bottom)
				(hide yes)
			)
		)
		(property "Datasheet" "https://www.kemet.com/en/us/capacitors/product/T520B337M006ATE040.html"
			(at 172.72 204.47 0)
			(effects
				(font
					(size 1.27 1.27)
					(thickness 0.15)
				)
				(justify left bottom)
				(hide yes)
			)
		)
		(property "Description" "Tantalum Polymer Capacitor, KO-CAP®, 330 µF, ± 20%, 6.3 V, B, 0.04 ohm, 1411 [3528 Metric]"
			(at 182.88 190.5 0)
			(effects
				(font
					(size 1.27 1.27)
				)
				(hide yes)
			)
		)
		(property "Val" "330u"
			(at 185.42 194.31 90)
			(effects
				(font
					(size 1.27 1.27)
					(thickness 0.15)
				)
				(justify left)
				(hide yes)
			)
		)
		(property "MPN" "T520B337M006ATE040"
			(at 170.18 204.47 0)
			(effects
				(font
					(size 1.27 1.27)
					(thickness 0.15)
				)
				(justify left bottom)
				(hide yes)
			)
		)
		(property "Manufacturer" "KEMET"
			(at 167.64 204.47 0)
			(effects
				(font
					(size 1.27 1.27)
					(thickness 0.15)
				)
				(justify left bottom)
				(hide yes)
			)
		)
		(property "License" "Apache-2.0"
			(at 165.1 204.47 0)
			(effects
				(font
					(size 1.27 1.27)
					(thickness 0.15)
				)
				(justify left bottom)
				(hide yes)
			)
		)
		(property "Author" "Antmicro"
			(at 162.56 204.47 0)
			(effects
				(font
					(size 1.27 1.27)
					(thickness 0.15)
				)
				(justify left bottom)
				(hide yes)
			)
		)
		(property "Voltage" "6.3V"
			(at 160.02 204.47 0)
			(effects
				(font
					(size 1.27 1.27)
				)
				(justify left bottom)
				(hide yes)
			)
		)
		(property "Dielectric" "template_dielectric"
			(at 157.48 204.47 0)
			(effects
				(font
					(size 1.27 1.27)
				)
				(justify left bottom)
				(hide yes)
			)
		)
		(property "Capacitance" "330u"
			(at 185.42 194.31 90)
			(effects
				(font
					(size 1.27 1.27)
				)
				(justify left)
			)
		)
		(property "Public" ""
			(at 154.94 204.47 0)
			(effects
				(font
					(size 1.27 1.27)
				)
				(justify left bottom)
				(hide yes)
			)
		)
		(pin "1"
		)
		(pin "2"
		)
		(instances
			(project "polarfire-som"
				(path ""
					(reference "C65")
					(unit 1)
				)
			)
		)
	)
	(symbol
		(lib_id "antmicroCapacitors0402:C_100n_0402")
		(at 176.53 168.91 90)
		(unit 1)
		(exclude_from_sim no)
		(in_bom yes)
		(on_board yes)
		(dnp no)
		(fields_autoplaced yes)
		(property "Reference" "C59"
			(at 179.07 165.0936 90)
			(effects
				(font
					(size 1.27 1.27)
					(thickness 0.15)
				)
				(justify right)
			)
		)
		(property "Value" "C_100n_0402"
			(at 186.69 148.59 0)
			(effects
				(font
					(size 1.27 1.27)
					(thickness 0.15)
				)
				(justify left bottom)
				(hide yes)
			)
		)
		(property "Footprint" "antmicro-footprints:C_0402_1005Metric"
			(at 189.23 148.59 0)
			(effects
				(font
					(size 1.27 1.27)
					(thickness 0.15)
				)
				(justify left bottom)
				(hide yes)
			)
		)
		(property "Datasheet" "https://www.murata.com/products/productdetail?partno=GRM155R61H104KE14%23"
			(at 191.77 148.59 0)
			(effects
				(font
					(size 1.27 1.27)
					(thickness 0.15)
				)
				(justify left bottom)
				(hide yes)
			)
		)
		(property "Description" "SMD Multilayer Ceramic Capacitor, 0.1 µF, 50 V, 0402 [1005 Metric], ± 10%, X5R, GRM Series"
			(at 176.53 168.91 0)
			(effects
				(font
					(size 1.27 1.27)
				)
				(hide yes)
			)
		)
		(property "MPN" "GRM155R61H104KE14D"
			(at 194.31 148.59 0)
			(effects
				(font
					(size 1.27 1.27)
					(thickness 0.15)
				)
				(justify left bottom)
				(hide yes)
			)
		)
		(property "Manufacturer" "Murata"
			(at 196.85 148.59 0)
			(effects
				(font
					(size 1.27 1.27)
					(thickness 0.15)
				)
				(justify left bottom)
				(hide yes)
			)
		)
		(property "License" "Apache-2.0"
			(at 199.39 148.59 0)
			(effects
				(font
					(size 1.27 1.27)
					(thickness 0.15)
				)
				(justify left bottom)
				(hide yes)
			)
		)
		(property "Author" "Antmicro"
			(at 201.93 148.59 0)
			(effects
				(font
					(size 1.27 1.27)
					(thickness 0.15)
				)
				(justify left bottom)
				(hide yes)
			)
		)
		(property "Val" "100n"
			(at 179.07 167.6336 90)
			(effects
				(font
					(size 1.27 1.27)
					(thickness 0.15)
				)
				(justify right)
			)
		)
		(property "Voltage" "50V"
			(at 204.47 148.59 0)
			(effects
				(font
					(size 1.27 1.27)
				)
				(justify left bottom)
				(hide yes)
			)
		)
		(property "Dielectric" "X5R"
			(at 207.01 148.59 0)
			(effects
				(font
					(size 1.27 1.27)
				)
				(justify left bottom)
				(hide yes)
			)
		)
		(property "Public" ""
			(at 209.55 148.59 0)
			(effects
				(font
					(size 1.27 1.27)
				)
				(justify left bottom)
				(hide yes)
			)
		)
		(pin "1"
		)
		(pin "2"
		)
		(instances
			(project "polarfire-som"
				(path ""
					(reference "C59")
					(unit 1)
				)
			)
		)
	)
	(symbol
		(lib_id "antmicroCapacitors0402:C_100n_0402")
		(at 24.13 196.85 90)
		(unit 1)
		(exclude_from_sim no)
		(in_bom yes)
		(on_board yes)
		(dnp no)
		(fields_autoplaced yes)
		(property "Reference" "C6"
			(at 26.67 193.0336 90)
			(effects
				(font
					(size 1.27 1.27)
					(thickness 0.15)
				)
				(justify right)
			)
		)
		(property "Value" "C_100n_0402"
			(at 34.29 176.53 0)
			(effects
				(font
					(size 1.27 1.27)
					(thickness 0.15)
				)
				(justify left bottom)
				(hide yes)
			)
		)
		(property "Footprint" "antmicro-footprints:C_0402_1005Metric"
			(at 36.83 176.53 0)
			(effects
				(font
					(size 1.27 1.27)
					(thickness 0.15)
				)
				(justify left bottom)
				(hide yes)
			)
		)
		(property "Datasheet" "https://www.murata.com/products/productdetail?partno=GRM155R61H104KE14%23"
			(at 39.37 176.53 0)
			(effects
				(font
					(size 1.27 1.27)
					(thickness 0.15)
				)
				(justify left bottom)
				(hide yes)
			)
		)
		(property "Description" "SMD Multilayer Ceramic Capacitor, 0.1 µF, 50 V, 0402 [1005 Metric], ± 10%, X5R, GRM Series"
			(at 24.13 196.85 0)
			(effects
				(font
					(size 1.27 1.27)
				)
				(hide yes)
			)
		)
		(property "MPN" "GRM155R61H104KE14D"
			(at 41.91 176.53 0)
			(effects
				(font
					(size 1.27 1.27)
					(thickness 0.15)
				)
				(justify left bottom)
				(hide yes)
			)
		)
		(property "Manufacturer" "Murata"
			(at 44.45 176.53 0)
			(effects
				(font
					(size 1.27 1.27)
					(thickness 0.15)
				)
				(justify left bottom)
				(hide yes)
			)
		)
		(property "License" "Apache-2.0"
			(at 46.99 176.53 0)
			(effects
				(font
					(size 1.27 1.27)
					(thickness 0.15)
				)
				(justify left bottom)
				(hide yes)
			)
		)
		(property "Author" "Antmicro"
			(at 49.53 176.53 0)
			(effects
				(font
					(size 1.27 1.27)
					(thickness 0.15)
				)
				(justify left bottom)
				(hide yes)
			)
		)
		(property "Val" "100n"
			(at 26.67 195.5736 90)
			(effects
				(font
					(size 1.27 1.27)
					(thickness 0.15)
				)
				(justify right)
			)
		)
		(property "Voltage" "50V"
			(at 52.07 176.53 0)
			(effects
				(font
					(size 1.27 1.27)
				)
				(justify left bottom)
				(hide yes)
			)
		)
		(property "Dielectric" "X5R"
			(at 54.61 176.53 0)
			(effects
				(font
					(size 1.27 1.27)
				)
				(justify left bottom)
				(hide yes)
			)
		)
		(property "Public" ""
			(at 57.15 176.53 0)
			(effects
				(font
					(size 1.27 1.27)
				)
				(justify left bottom)
				(hide yes)
			)
		)
		(pin "1"
		)
		(pin "2"
		)
		(instances
			(project "polarfire-som"
				(path ""
					(reference "C6")
					(unit 1)
				)
			)
		)
	)
	(symbol
		(lib_id "antmicroCapacitors0402:C_100n_0402")
		(at 132.08 220.98 90)
		(unit 1)
		(exclude_from_sim no)
		(in_bom yes)
		(on_board yes)
		(dnp no)
		(fields_autoplaced yes)
		(property "Reference" "C41"
			(at 134.62 217.1636 90)
			(effects
				(font
					(size 1.27 1.27)
					(thickness 0.15)
				)
				(justify right)
			)
		)
		(property "Value" "C_100n_0402"
			(at 142.24 200.66 0)
			(effects
				(font
					(size 1.27 1.27)
					(thickness 0.15)
				)
				(justify left bottom)
				(hide yes)
			)
		)
		(property "Footprint" "antmicro-footprints:C_0402_1005Metric"
			(at 144.78 200.66 0)
			(effects
				(font
					(size 1.27 1.27)
					(thickness 0.15)
				)
				(justify left bottom)
				(hide yes)
			)
		)
		(property "Datasheet" "https://www.murata.com/products/productdetail?partno=GRM155R61H104KE14%23"
			(at 147.32 200.66 0)
			(effects
				(font
					(size 1.27 1.27)
					(thickness 0.15)
				)
				(justify left bottom)
				(hide yes)
			)
		)
		(property "Description" "SMD Multilayer Ceramic Capacitor, 0.1 µF, 50 V, 0402 [1005 Metric], ± 10%, X5R, GRM Series"
			(at 132.08 220.98 0)
			(effects
				(font
					(size 1.27 1.27)
				)
				(hide yes)
			)
		)
		(property "MPN" "GRM155R61H104KE14D"
			(at 149.86 200.66 0)
			(effects
				(font
					(size 1.27 1.27)
					(thickness 0.15)
				)
				(justify left bottom)
				(hide yes)
			)
		)
		(property "Manufacturer" "Murata"
			(at 152.4 200.66 0)
			(effects
				(font
					(size 1.27 1.27)
					(thickness 0.15)
				)
				(justify left bottom)
				(hide yes)
			)
		)
		(property "License" "Apache-2.0"
			(at 154.94 200.66 0)
			(effects
				(font
					(size 1.27 1.27)
					(thickness 0.15)
				)
				(justify left bottom)
				(hide yes)
			)
		)
		(property "Author" "Antmicro"
			(at 157.48 200.66 0)
			(effects
				(font
					(size 1.27 1.27)
					(thickness 0.15)
				)
				(justify left bottom)
				(hide yes)
			)
		)
		(property "Val" "100n"
			(at 134.62 219.7036 90)
			(effects
				(font
					(size 1.27 1.27)
					(thickness 0.15)
				)
				(justify right)
			)
		)
		(property "Voltage" "50V"
			(at 160.02 200.66 0)
			(effects
				(font
					(size 1.27 1.27)
				)
				(justify left bottom)
				(hide yes)
			)
		)
		(property "Dielectric" "X5R"
			(at 162.56 200.66 0)
			(effects
				(font
					(size 1.27 1.27)
				)
				(justify left bottom)
				(hide yes)
			)
		)
		(property "Public" ""
			(at 165.1 200.66 0)
			(effects
				(font
					(size 1.27 1.27)
				)
				(justify left bottom)
				(hide yes)
			)
		)
		(pin "1"
		)
		(pin "2"
		)
		(instances
			(project "polarfire-som"
				(path ""
					(reference "C41")
					(unit 1)
				)
			)
		)
	)
	(symbol
		(lib_id "antmicropower:PWR_FLAG")
		(at 132.08 213.36 0)
		(unit 1)
		(exclude_from_sim no)
		(in_bom yes)
		(on_board yes)
		(dnp no)
		(property "Reference" "#FLG06"
			(at 132.08 211.455 0)
			(effects
				(font
					(size 1.27 1.27)
				)
				(hide yes)
			)
		)
		(property "Value" "PWR_FLAG"
			(at 132.08 209.296 0)
			(effects
				(font
					(size 1.27 1.27)
				)
			)
		)
		(property "Footprint" ""
			(at 132.08 213.36 0)
			(effects
				(font
					(size 1.27 1.27)
				)
				(hide yes)
			)
		)
		(property "Datasheet" ""
			(at 132.08 213.36 0)
			(effects
				(font
					(size 1.27 1.27)
				)
				(hide yes)
			)
		)
		(property "Description" ""
			(at 132.08 213.36 0)
			(effects
				(font
					(size 1.27 1.27)
				)
				(hide yes)
			)
		)
		(pin "1"
		)
		(instances
			(project ""
				(path ""
					(reference "#FLG06")
					(unit 1)
				)
			)
		)
	)
	(symbol
		(lib_id "antmicropower:GND")
		(at 193.04 96.52 0)
		(unit 1)
		(exclude_from_sim no)
		(in_bom yes)
		(on_board yes)
		(dnp no)
		(property "Reference" "#PWR040"
			(at 201.93 99.06 0)
			(effects
				(font
					(size 1.27 1.27)
					(thickness 0.15)
				)
				(justify left bottom)
				(hide yes)
			)
		)
		(property "Value" "GND"
			(at 193.04 100.33 0)
			(effects
				(font
					(size 1.27 1.27)
					(thickness 0.15)
				)
			)
		)
		(property "Footprint" ""
			(at 201.93 104.14 0)
			(effects
				(font
					(size 1.27 1.27)
					(thickness 0.15)
				)
				(justify left bottom)
				(hide yes)
			)
		)
		(property "Datasheet" ""
			(at 201.93 109.22 0)
			(effects
				(font
					(size 1.27 1.27)
					(thickness 0.15)
				)
				(justify left bottom)
				(hide yes)
			)
		)
		(property "Description" ""
			(at 193.04 96.52 0)
			(effects
				(font
					(size 1.27 1.27)
				)
				(hide yes)
			)
		)
		(property "Author" "Antmicro"
			(at 201.93 104.14 0)
			(effects
				(font
					(size 1.27 1.27)
					(thickness 0.15)
				)
				(justify left bottom)
				(hide yes)
			)
		)
		(property "License" "Apache-2.0"
			(at 201.93 106.68 0)
			(effects
				(font
					(size 1.27 1.27)
					(thickness 0.15)
				)
				(justify left bottom)
				(hide yes)
			)
		)
		(pin "1"
		)
		(instances
			(project "polarfire-som"
				(path ""
					(reference "#PWR040")
					(unit 1)
				)
			)
		)
	)
	(symbol
		(lib_id "antmicroCapacitors0402:C_47n_0402")
		(at 156.21 168.91 90)
		(unit 1)
		(exclude_from_sim no)
		(in_bom yes)
		(on_board yes)
		(dnp no)
		(fields_autoplaced yes)
		(property "Reference" "C48"
			(at 158.75 165.0936 90)
			(effects
				(font
					(size 1.27 1.27)
					(thickness 0.15)
				)
				(justify right)
			)
		)
		(property "Value" "C_47n_0402"
			(at 166.37 148.59 0)
			(effects
				(font
					(size 1.27 1.27)
					(thickness 0.15)
				)
				(justify left bottom)
				(hide yes)
			)
		)
		(property "Footprint" "antmicro-footprints:C_0402_1005Metric"
			(at 168.91 148.59 0)
			(effects
				(font
					(size 1.27 1.27)
					(thickness 0.15)
				)
				(justify left bottom)
				(hide yes)
			)
		)
		(property "Datasheet" "https://www.murata.com/en-us/products/productdetail?partno=GRM155R61C473KA01%23"
			(at 171.45 148.59 0)
			(effects
				(font
					(size 1.27 1.27)
					(thickness 0.15)
				)
				(justify left bottom)
				(hide yes)
			)
		)
		(property "Description" "SMD Multilayer Ceramic Capacitor, 47000 pF, 16 V, 0402 [1005 Metric], ± 10%, X5R, MC"
			(at 156.21 168.91 0)
			(effects
				(font
					(size 1.27 1.27)
				)
				(hide yes)
			)
		)
		(property "MPN" "GRM155R61C473KA01D"
			(at 173.99 148.59 0)
			(effects
				(font
					(size 1.27 1.27)
					(thickness 0.15)
				)
				(justify left bottom)
				(hide yes)
			)
		)
		(property "Manufacturer" "Murata"
			(at 176.53 148.59 0)
			(effects
				(font
					(size 1.27 1.27)
					(thickness 0.15)
				)
				(justify left bottom)
				(hide yes)
			)
		)
		(property "License" "Apache-2.0"
			(at 179.07 148.59 0)
			(effects
				(font
					(size 1.27 1.27)
					(thickness 0.15)
				)
				(justify left bottom)
				(hide yes)
			)
		)
		(property "Author" "Antmicro"
			(at 181.61 148.59 0)
			(effects
				(font
					(size 1.27 1.27)
					(thickness 0.15)
				)
				(justify left bottom)
				(hide yes)
			)
		)
		(property "Val" "47n"
			(at 158.75 167.6336 90)
			(effects
				(font
					(size 1.27 1.27)
					(thickness 0.15)
				)
				(justify right)
			)
		)
		(property "Voltage" "10V"
			(at 184.15 148.59 0)
			(effects
				(font
					(size 1.27 1.27)
				)
				(justify left bottom)
				(hide yes)
			)
		)
		(property "Dielectric" "X5R"
			(at 186.69 148.59 0)
			(effects
				(font
					(size 1.27 1.27)
				)
				(justify left bottom)
				(hide yes)
			)
		)
		(property "Public" ""
			(at 189.23 148.59 0)
			(effects
				(font
					(size 1.27 1.27)
				)
				(justify left bottom)
				(hide yes)
			)
		)
		(pin "1"
		)
		(pin "2"
		)
		(instances
			(project "polarfire-som"
				(path ""
					(reference "C48")
					(unit 1)
				)
			)
		)
	)
	(symbol
		(lib_id "antmicropower:+1V1")
		(at 20.32 161.29 0)
		(unit 1)
		(exclude_from_sim no)
		(in_bom yes)
		(on_board yes)
		(dnp no)
		(property "Reference" "#PWR0232"
			(at 20.32 165.1 0)
			(effects
				(font
					(size 1.27 1.27)
				)
				(hide yes)
			)
		)
		(property "Value" "+1V1"
			(at 20.32 157.48 0)
			(effects
				(font
					(size 1.27 1.27)
				)
			)
		)
		(property "Footprint" ""
			(at 20.32 161.29 0)
			(effects
				(font
					(size 1.27 1.27)
				)
				(hide yes)
			)
		)
		(property "Datasheet" ""
			(at 20.32 161.29 0)
			(effects
				(font
					(size 1.27 1.27)
				)
				(hide yes)
			)
		)
		(property "Description" ""
			(at 20.32 161.29 0)
			(effects
				(font
					(size 1.27 1.27)
				)
				(hide yes)
			)
		)
		(pin "1"
		)
		(instances
			(project "polarfire-som"
				(path ""
					(reference "#PWR0232")
					(unit 1)
				)
			)
		)
	)
	(symbol
		(lib_id "antmicropower:GND")
		(at 115.57 279.4 0)
		(unit 1)
		(exclude_from_sim no)
		(in_bom yes)
		(on_board yes)
		(dnp no)
		(property "Reference" "#PWR0281"
			(at 124.46 281.94 0)
			(effects
				(font
					(size 1.27 1.27)
					(thickness 0.15)
				)
				(justify left bottom)
				(hide yes)
			)
		)
		(property "Value" "GND"
			(at 115.57 283.21 0)
			(effects
				(font
					(size 1.27 1.27)
					(thickness 0.15)
				)
			)
		)
		(property "Footprint" ""
			(at 124.46 287.02 0)
			(effects
				(font
					(size 1.27 1.27)
					(thickness 0.15)
				)
				(justify left bottom)
				(hide yes)
			)
		)
		(property "Datasheet" ""
			(at 124.46 292.1 0)
			(effects
				(font
					(size 1.27 1.27)
					(thickness 0.15)
				)
				(justify left bottom)
				(hide yes)
			)
		)
		(property "Description" ""
			(at 115.57 279.4 0)
			(effects
				(font
					(size 1.27 1.27)
				)
				(hide yes)
			)
		)
		(property "Author" "Antmicro"
			(at 124.46 287.02 0)
			(effects
				(font
					(size 1.27 1.27)
					(thickness 0.15)
				)
				(justify left bottom)
				(hide yes)
			)
		)
		(property "License" "Apache-2.0"
			(at 124.46 289.56 0)
			(effects
				(font
					(size 1.27 1.27)
					(thickness 0.15)
				)
				(justify left bottom)
				(hide yes)
			)
		)
		(pin "1"
		)
		(instances
			(project "polarfire-som"
				(path ""
					(reference "#PWR0281")
					(unit 1)
				)
			)
		)
	)
	(symbol
		(lib_id "antmicroCapacitors0402:C_4n7_0402")
		(at 119.38 195.58 90)
		(unit 1)
		(exclude_from_sim no)
		(in_bom yes)
		(on_board yes)
		(dnp no)
		(fields_autoplaced yes)
		(property "Reference" "C38"
			(at 121.92 191.7636 90)
			(effects
				(font
					(size 1.27 1.27)
					(thickness 0.15)
				)
				(justify right)
			)
		)
		(property "Value" "C_4n7_0402"
			(at 129.54 175.26 0)
			(effects
				(font
					(size 1.27 1.27)
					(thickness 0.15)
				)
				(justify left bottom)
				(hide yes)
			)
		)
		(property "Footprint" "antmicro-footprints:C_0402_1005Metric"
			(at 132.08 175.26 0)
			(effects
				(font
					(size 1.27 1.27)
					(thickness 0.15)
				)
				(justify left bottom)
				(hide yes)
			)
		)
		(property "Datasheet" "https://product.tdk.com/en/search/capacitor/ceramic/mlcc/info?part_no=CGA2B3X7S2A472K050BB"
			(at 134.62 175.26 0)
			(effects
				(font
					(size 1.27 1.27)
					(thickness 0.15)
				)
				(justify left bottom)
				(hide yes)
			)
		)
		(property "Description" "SMD Multilayer Ceramic Capacitor, 4700 pF, 100 V, 0402 [1005 Metric], ± 10%, X7S, CGA"
			(at 119.38 195.58 0)
			(effects
				(font
					(size 1.27 1.27)
				)
				(hide yes)
			)
		)
		(property "MPN" "CGA2B3X7S2A472K050BB"
			(at 137.16 175.26 0)
			(effects
				(font
					(size 1.27 1.27)
					(thickness 0.15)
				)
				(justify left bottom)
				(hide yes)
			)
		)
		(property "Manufacturer" "TDK"
			(at 139.7 175.26 0)
			(effects
				(font
					(size 1.27 1.27)
					(thickness 0.15)
				)
				(justify left bottom)
				(hide yes)
			)
		)
		(property "License" "Apache-2.0"
			(at 142.24 175.26 0)
			(effects
				(font
					(size 1.27 1.27)
					(thickness 0.15)
				)
				(justify left bottom)
				(hide yes)
			)
		)
		(property "Author" "Antmicro"
			(at 144.78 175.26 0)
			(effects
				(font
					(size 1.27 1.27)
					(thickness 0.15)
				)
				(justify left bottom)
				(hide yes)
			)
		)
		(property "Val" "4n7"
			(at 121.92 194.3036 90)
			(effects
				(font
					(size 1.27 1.27)
					(thickness 0.15)
				)
				(justify right)
			)
		)
		(property "Voltage" "25V"
			(at 147.32 175.26 0)
			(effects
				(font
					(size 1.27 1.27)
				)
				(justify left bottom)
				(hide yes)
			)
		)
		(property "Dielectric" "X7R"
			(at 149.86 175.26 0)
			(effects
				(font
					(size 1.27 1.27)
				)
				(justify left bottom)
				(hide yes)
			)
		)
		(property "Public" ""
			(at 152.4 175.26 0)
			(effects
				(font
					(size 1.27 1.27)
				)
				(justify left bottom)
				(hide yes)
			)
		)
		(pin "1"
		)
		(pin "2"
		)
		(instances
			(project "polarfire-som"
				(path ""
					(reference "C38")
					(unit 1)
				)
			)
		)
	)
	(symbol
		(lib_id "antmicroCapacitors0603:C_47u_0603")
		(at 139.7 246.38 90)
		(unit 1)
		(exclude_from_sim no)
		(in_bom yes)
		(on_board yes)
		(dnp no)
		(fields_autoplaced yes)
		(property "Reference" "C47"
			(at 142.24 242.5636 90)
			(effects
				(font
					(size 1.27 1.27)
					(thickness 0.15)
				)
				(justify right)
			)
		)
		(property "Value" "C_47u_0603"
			(at 149.86 226.06 0)
			(effects
				(font
					(size 1.27 1.27)
					(thickness 0.15)
				)
				(justify left bottom)
				(hide yes)
			)
		)
		(property "Footprint" "antmicro-footprints:C_0603_1608Metric"
			(at 152.4 226.06 0)
			(effects
				(font
					(size 1.27 1.27)
					(thickness 0.15)
				)
				(justify left bottom)
				(hide yes)
			)
		)
		(property "Datasheet" "https://www.murata.com/products/productdetail?partno=GRM188R60J476ME15%23"
			(at 154.94 226.06 0)
			(effects
				(font
					(size 1.27 1.27)
					(thickness 0.15)
				)
				(justify left bottom)
				(hide yes)
			)
		)
		(property "Description" "SMD Multilayer Ceramic Capacitor, 47 µF, 6.3 V, 0603 [1608 Metric], ± 20%, X5R, GRM Series"
			(at 139.7 246.38 0)
			(effects
				(font
					(size 1.27 1.27)
				)
				(hide yes)
			)
		)
		(property "MPN" "GRM188R60J476ME15D"
			(at 157.48 226.06 0)
			(effects
				(font
					(size 1.27 1.27)
					(thickness 0.15)
				)
				(justify left bottom)
				(hide yes)
			)
		)
		(property "Manufacturer" "Murata"
			(at 160.02 226.06 0)
			(effects
				(font
					(size 1.27 1.27)
					(thickness 0.15)
				)
				(justify left bottom)
				(hide yes)
			)
		)
		(property "License" "Apache-2.0"
			(at 162.56 226.06 0)
			(effects
				(font
					(size 1.27 1.27)
					(thickness 0.15)
				)
				(justify left bottom)
				(hide yes)
			)
		)
		(property "Author" "Antmicro"
			(at 165.1 226.06 0)
			(effects
				(font
					(size 1.27 1.27)
					(thickness 0.15)
				)
				(justify left bottom)
				(hide yes)
			)
		)
		(property "Val" "47u"
			(at 142.24 245.1036 90)
			(effects
				(font
					(size 1.27 1.27)
					(thickness 0.15)
				)
				(justify right)
			)
		)
		(property "Voltage" "50V"
			(at 167.64 226.06 0)
			(effects
				(font
					(size 1.27 1.27)
				)
				(justify left bottom)
				(hide yes)
			)
		)
		(property "Dielectric" "X7R"
			(at 170.18 226.06 0)
			(effects
				(font
					(size 1.27 1.27)
				)
				(justify left bottom)
				(hide yes)
			)
		)
		(property "Capacitance" "47u"
			(at 142.24 245.11 90)
			(effects
				(font
					(size 1.27 1.27)
				)
				(justify right)
				(hide yes)
			)
		)
		(property "Public" ""
			(at 172.72 226.06 0)
			(effects
				(font
					(size 1.27 1.27)
				)
				(justify left bottom)
				(hide yes)
			)
		)
		(pin "1"
		)
		(pin "2"
		)
		(instances
			(project "polarfire-som"
				(path ""
					(reference "C47")
					(unit 1)
				)
			)
		)
	)
	(symbol
		(lib_id "antmicroCapacitors0603:C_47u_0603")
		(at 182.88 246.38 90)
		(unit 1)
		(exclude_from_sim no)
		(in_bom yes)
		(on_board yes)
		(dnp no)
		(fields_autoplaced yes)
		(property "Reference" "C67"
			(at 185.42 242.5636 90)
			(effects
				(font
					(size 1.27 1.27)
					(thickness 0.15)
				)
				(justify right)
			)
		)
		(property "Value" "C_47u_0603"
			(at 193.04 226.06 0)
			(effects
				(font
					(size 1.27 1.27)
					(thickness 0.15)
				)
				(justify left bottom)
				(hide yes)
			)
		)
		(property "Footprint" "antmicro-footprints:C_0603_1608Metric"
			(at 195.58 226.06 0)
			(effects
				(font
					(size 1.27 1.27)
					(thickness 0.15)
				)
				(justify left bottom)
				(hide yes)
			)
		)
		(property "Datasheet" "https://www.murata.com/products/productdetail?partno=GRM188R60J476ME15%23"
			(at 198.12 226.06 0)
			(effects
				(font
					(size 1.27 1.27)
					(thickness 0.15)
				)
				(justify left bottom)
				(hide yes)
			)
		)
		(property "Description" "SMD Multilayer Ceramic Capacitor, 47 µF, 6.3 V, 0603 [1608 Metric], ± 20%, X5R, GRM Series"
			(at 182.88 246.38 0)
			(effects
				(font
					(size 1.27 1.27)
				)
				(hide yes)
			)
		)
		(property "MPN" "GRM188R60J476ME15D"
			(at 200.66 226.06 0)
			(effects
				(font
					(size 1.27 1.27)
					(thickness 0.15)
				)
				(justify left bottom)
				(hide yes)
			)
		)
		(property "Manufacturer" "Murata"
			(at 203.2 226.06 0)
			(effects
				(font
					(size 1.27 1.27)
					(thickness 0.15)
				)
				(justify left bottom)
				(hide yes)
			)
		)
		(property "License" "Apache-2.0"
			(at 205.74 226.06 0)
			(effects
				(font
					(size 1.27 1.27)
					(thickness 0.15)
				)
				(justify left bottom)
				(hide yes)
			)
		)
		(property "Author" "Antmicro"
			(at 208.28 226.06 0)
			(effects
				(font
					(size 1.27 1.27)
					(thickness 0.15)
				)
				(justify left bottom)
				(hide yes)
			)
		)
		(property "Val" "47u"
			(at 185.42 245.1036 90)
			(effects
				(font
					(size 1.27 1.27)
					(thickness 0.15)
				)
				(justify right)
			)
		)
		(property "Voltage" "50V"
			(at 210.82 226.06 0)
			(effects
				(font
					(size 1.27 1.27)
				)
				(justify left bottom)
				(hide yes)
			)
		)
		(property "Dielectric" "X7R"
			(at 213.36 226.06 0)
			(effects
				(font
					(size 1.27 1.27)
				)
				(justify left bottom)
				(hide yes)
			)
		)
		(property "Capacitance" "47u"
			(at 185.42 245.11 90)
			(effects
				(font
					(size 1.27 1.27)
				)
				(justify right)
				(hide yes)
			)
		)
		(property "Public" ""
			(at 215.9 226.06 0)
			(effects
				(font
					(size 1.27 1.27)
				)
				(justify left bottom)
				(hide yes)
			)
		)
		(pin "1"
		)
		(pin "2"
		)
		(instances
			(project "polarfire-som"
				(path ""
					(reference "C67")
					(unit 1)
				)
			)
		)
	)
	(symbol
		(lib_id "antmicroCapacitors0402:C_10u_0402")
		(at 71.12 220.98 90)
		(unit 1)
		(exclude_from_sim no)
		(in_bom yes)
		(on_board yes)
		(dnp no)
		(fields_autoplaced yes)
		(property "Reference" "C23"
			(at 74.295 217.1635 90)
			(effects
				(font
					(size 1.27 1.27)
					(thickness 0.15)
				)
				(justify right)
			)
		)
		(property "Value" "C_10u_0402"
			(at 81.28 200.66 0)
			(effects
				(font
					(size 1.27 1.27)
					(thickness 0.15)
				)
				(justify left bottom)
				(hide yes)
			)
		)
		(property "Footprint" "antmicro-footprints:C_0402_1005Metric"
			(at 83.82 200.66 0)
			(effects
				(font
					(size 1.27 1.27)
					(thickness 0.15)
				)
				(justify left bottom)
				(hide yes)
			)
		)
		(property "Datasheet" "https://www.yageo.com/en/Chart/Download/pdf/CC0402MRX5R5BB106"
			(at 86.36 200.66 0)
			(effects
				(font
					(size 1.27 1.27)
					(thickness 0.15)
				)
				(justify left bottom)
				(hide yes)
			)
		)
		(property "Description" "SMD Multilayer Ceramic Capacitor, 10 µF, 6.3 V, 0402 [1005 Metric], ± 20%, X5R, CC Series"
			(at 71.12 220.98 0)
			(effects
				(font
					(size 1.27 1.27)
				)
				(hide yes)
			)
		)
		(property "MPN" "CC0402MRX5R5BB106"
			(at 88.9 200.66 0)
			(effects
				(font
					(size 1.27 1.27)
					(thickness 0.15)
				)
				(justify left bottom)
				(hide yes)
			)
		)
		(property "Manufacturer" "YAGEO"
			(at 91.44 200.66 0)
			(effects
				(font
					(size 1.27 1.27)
					(thickness 0.15)
				)
				(justify left bottom)
				(hide yes)
			)
		)
		(property "License" "Apache-2.0"
			(at 93.98 200.66 0)
			(effects
				(font
					(size 1.27 1.27)
					(thickness 0.15)
				)
				(justify left bottom)
				(hide yes)
			)
		)
		(property "Author" "Antmicro"
			(at 96.52 200.66 0)
			(effects
				(font
					(size 1.27 1.27)
					(thickness 0.15)
				)
				(justify left bottom)
				(hide yes)
			)
		)
		(property "Val" "10u"
			(at 74.295 219.7035 90)
			(effects
				(font
					(size 1.27 1.27)
					(thickness 0.15)
				)
				(justify right)
			)
		)
		(property "Voltage" ""
			(at 99.06 200.66 0)
			(effects
				(font
					(size 1.27 1.27)
				)
				(justify left bottom)
				(hide yes)
			)
		)
		(property "Dielectric" ""
			(at 101.6 200.66 0)
			(effects
				(font
					(size 1.27 1.27)
				)
				(justify left bottom)
				(hide yes)
			)
		)
		(property "Public" ""
			(at 104.14 200.66 0)
			(effects
				(font
					(size 1.27 1.27)
				)
				(justify left bottom)
				(hide yes)
			)
		)
		(pin "1"
		)
		(pin "2"
		)
		(instances
			(project "polarfire-som"
				(path ""
					(reference "C23")
					(unit 1)
				)
			)
		)
	)
	(symbol
		(lib_id "antmicropower:GND")
		(at 146.05 279.4 0)
		(unit 1)
		(exclude_from_sim no)
		(in_bom yes)
		(on_board yes)
		(dnp no)
		(property "Reference" "#PWR0172"
			(at 154.94 281.94 0)
			(effects
				(font
					(size 1.27 1.27)
					(thickness 0.15)
				)
				(justify left bottom)
				(hide yes)
			)
		)
		(property "Value" "GND"
			(at 146.05 283.21 0)
			(effects
				(font
					(size 1.27 1.27)
					(thickness 0.15)
				)
			)
		)
		(property "Footprint" ""
			(at 154.94 287.02 0)
			(effects
				(font
					(size 1.27 1.27)
					(thickness 0.15)
				)
				(justify left bottom)
				(hide yes)
			)
		)
		(property "Datasheet" ""
			(at 154.94 292.1 0)
			(effects
				(font
					(size 1.27 1.27)
					(thickness 0.15)
				)
				(justify left bottom)
				(hide yes)
			)
		)
		(property "Description" ""
			(at 146.05 279.4 0)
			(effects
				(font
					(size 1.27 1.27)
				)
				(hide yes)
			)
		)
		(property "Author" "Antmicro"
			(at 154.94 287.02 0)
			(effects
				(font
					(size 1.27 1.27)
					(thickness 0.15)
				)
				(justify left bottom)
				(hide yes)
			)
		)
		(property "License" "Apache-2.0"
			(at 154.94 289.56 0)
			(effects
				(font
					(size 1.27 1.27)
					(thickness 0.15)
				)
				(justify left bottom)
				(hide yes)
			)
		)
		(pin "1"
		)
		(instances
			(project "polarfire-som"
				(path ""
					(reference "#PWR0172")
					(unit 1)
				)
			)
		)
	)
	(symbol
		(lib_id "antmicropower:+3V3")
		(at 24.13 214.63 0)
		(unit 1)
		(exclude_from_sim no)
		(in_bom yes)
		(on_board yes)
		(dnp no)
		(property "Reference" "#PWR0227"
			(at 39.37 214.63 0)
			(effects
				(font
					(size 1.27 1.27)
					(thickness 0.15)
				)
				(justify left bottom)
				(hide yes)
			)
		)
		(property "Value" "+3V3"
			(at 24.13 210.82 0)
			(effects
				(font
					(size 1.27 1.27)
					(thickness 0.15)
				)
			)
		)
		(property "Footprint" ""
			(at 39.37 222.25 0)
			(effects
				(font
					(size 1.27 1.27)
					(thickness 0.15)
				)
				(justify left bottom)
				(hide yes)
			)
		)
		(property "Datasheet" ""
			(at 39.37 224.79 0)
			(effects
				(font
					(size 1.27 1.27)
					(thickness 0.15)
				)
				(justify left bottom)
				(hide yes)
			)
		)
		(property "Description" ""
			(at 24.13 214.63 0)
			(effects
				(font
					(size 1.27 1.27)
				)
				(hide yes)
			)
		)
		(property "Author" "Antmicro"
			(at 39.37 217.17 0)
			(effects
				(font
					(size 1.27 1.27)
					(thickness 0.15)
				)
				(justify left bottom)
				(hide yes)
			)
		)
		(property "License" "Apache-2.0"
			(at 39.37 219.71 0)
			(effects
				(font
					(size 1.27 1.27)
					(thickness 0.15)
				)
				(justify left bottom)
				(hide yes)
			)
		)
		(pin "1"
		)
		(instances
			(project "polarfire-som"
				(path ""
					(reference "#PWR0227")
					(unit 1)
				)
			)
		)
	)
)
